G04 ================== begin FILE IDENTIFICATION RECORD ==================*
G04 Layout Name:  12004-1.brd*
G04 Film Name:    DRILL*
G04 File Format:  Gerber RS274X*
G04 File Origin:  Cadence Allegro 16.2-S033*
G04 Origin Date:  Tue Oct 16 14:35:51 2012*
G04 *
G04 Layer:  MANUFACTURING/NCLEGEND-1-8*
G04 Layer:  MANUFACTURING/DRILL SIZE*
G04 Layer:  DRAWING FORMAT/LAYER_PCB_STORY*
G04 Layer:  DRAWING FORMAT/LAYER_DRILL*
G04 Layer:  BOARD GEOMETRY/PANEL_OUTLINE*
G04 *
G04 Offset:    (0.00 0.00)*
G04 Mirror:    No*
G04 Mode:      Positive*
G04 Rotation:  0*
G04 FullContactRelief:  No*
G04 UndefLineWidth:     6.00*
G04 ================== end FILE IDENTIFICATION RECORD ====================*
%FSLAX35Y35*MOIN*%
%IR0*IPPOS*OFA0.00000B0.00000*MIA0B0*SFA1.00000B1.00000*%
%AMMACRO21*
1,1,.006,0.0,.0495*
20,1,.006,0.0,.0495,0.0,.0495,0.0*
1,1,.006,0.0,.0495*
20,1,.006,0.0,.0495,.008596,.048748,0.0*
1,1,.006,.008596,.048748*
20,1,.006,.008596,.048748,.01693,.046515,0.0*
1,1,.006,.01693,.046515*
20,1,.006,.01693,.046515,.02475,.042868,0.0*
1,1,.006,.02475,.042868*
20,1,.006,.02475,.042868,.031818,.037919,0.0*
1,1,.006,.031818,.037919*
20,1,.006,.031818,.037919,.037919,.031818,0.0*
1,1,.006,.037919,.031818*
20,1,.006,.037919,.031818,.042868,.02475,0.0*
1,1,.006,.042868,.02475*
20,1,.006,.042868,.02475,.046515,.01693,0.0*
1,1,.006,.046515,.01693*
20,1,.006,.046515,.01693,.048748,.008596,0.0*
1,1,.006,.048748,.008596*
20,1,.006,.048748,.008596,.0495,0.0,0.0*
1,1,.006,.0495,0.0*
20,1,.006,.0495,0.0,.048748,-.008596,0.0*
1,1,.006,.048748,-.008596*
20,1,.006,.048748,-.008596,.046515,-.01693,0.0*
1,1,.006,.046515,-.01693*
20,1,.006,.046515,-.01693,.042868,-.02475,0.0*
1,1,.006,.042868,-.02475*
20,1,.006,.042868,-.02475,.037919,-.031818,0.0*
1,1,.006,.037919,-.031818*
20,1,.006,.037919,-.031818,.031818,-.037919,0.0*
1,1,.006,.031818,-.037919*
20,1,.006,.031818,-.037919,.02475,-.042868,0.0*
1,1,.006,.02475,-.042868*
20,1,.006,.02475,-.042868,.01693,-.046515,0.0*
1,1,.006,.01693,-.046515*
20,1,.006,.01693,-.046515,.008596,-.048748,0.0*
1,1,.006,.008596,-.048748*
20,1,.006,.008596,-.048748,0.0,-.0495,0.0*
1,1,.006,0.0,-.0495*
20,1,.006,0.0,-.0495,0.0,-.0495,0.0*
1,1,.006,0.0,-.0495*
20,1,.006,0.0,-.0495,-.008596,-.048748,0.0*
1,1,.006,-.008596,-.048748*
20,1,.006,-.008596,-.048748,-.01693,-.046515,0.0*
1,1,.006,-.01693,-.046515*
20,1,.006,-.01693,-.046515,-.02475,-.042868,0.0*
1,1,.006,-.02475,-.042868*
20,1,.006,-.02475,-.042868,-.031818,-.037919,0.0*
1,1,.006,-.031818,-.037919*
20,1,.006,-.031818,-.037919,-.037919,-.031818,0.0*
1,1,.006,-.037919,-.031818*
20,1,.006,-.037919,-.031818,-.042868,-.02475,0.0*
1,1,.006,-.042868,-.02475*
20,1,.006,-.042868,-.02475,-.046515,-.01693,0.0*
1,1,.006,-.046515,-.01693*
20,1,.006,-.046515,-.01693,-.048748,-.008596,0.0*
1,1,.006,-.048748,-.008596*
20,1,.006,-.048748,-.008596,-.0495,0.0,0.0*
1,1,.006,-.0495,0.0*
20,1,.006,-.0495,0.0,-.048748,.008596,0.0*
1,1,.006,-.048748,.008596*
20,1,.006,-.048748,.008596,-.046515,.01693,0.0*
1,1,.006,-.046515,.01693*
20,1,.006,-.046515,.01693,-.042868,.02475,0.0*
1,1,.006,-.042868,.02475*
20,1,.006,-.042868,.02475,-.037919,.031818,0.0*
1,1,.006,-.037919,.031818*
20,1,.006,-.037919,.031818,-.031818,.037919,0.0*
1,1,.006,-.031818,.037919*
20,1,.006,-.031818,.037919,-.02475,.042868,0.0*
1,1,.006,-.02475,.042868*
20,1,.006,-.02475,.042868,-.01693,.046515,0.0*
1,1,.006,-.01693,.046515*
20,1,.006,-.01693,.046515,-.008596,.048748,0.0*
1,1,.006,-.008596,.048748*
20,1,.006,-.008596,.048748,0.0,.0495,0.0*
1,1,.006,0.0,.0495*
1,1,.006,0.0,-.02475*
20,1,.006,0.0,-.02475,.00577,-.02393,0.0*
1,1,.006,.00577,-.02393*
20,1,.006,.00577,-.02393,.01237,-.02145,0.0*
1,1,.006,.01237,-.02145*
20,1,.006,.01237,-.02145,.0165,-.01733,0.0*
1,1,.006,.0165,-.01733*
20,1,.006,.0165,-.01733,.01815,-.01155,0.0*
1,1,.006,.01815,-.01155*
20,1,.006,.01815,-.01155,.0165,-.00578,0.0*
1,1,.006,.0165,-.00578*
20,1,.006,.0165,-.00578,.01155,-.00083,0.0*
1,1,.006,.01155,-.00083*
20,1,.006,.01155,-.00083,.00412,.00165,0.0*
1,1,.006,.00412,.00165*
20,1,.006,.00412,.00165,-.00412,.00165,0.0*
1,1,.006,-.00412,.00165*
20,1,.006,-.00412,.00165,-.00908,.0033,0.0*
1,1,.006,-.00908,.0033*
20,1,.006,-.00908,.0033,-.0132,.00742,0.0*
1,1,.006,-.0132,.00742*
20,1,.006,-.0132,.00742,-.01485,.0132,0.0*
1,1,.006,-.01485,.0132*
20,1,.006,-.01485,.0132,-.01237,.01897,0.0*
1,1,.006,-.01237,.01897*
20,1,.006,-.01237,.01897,-.0066,.0231,0.0*
1,1,.006,-.0066,.0231*
20,1,.006,-.0066,.0231,0.0,.02475,0.0*
1,1,.006,0.0,.02475*
20,1,.006,0.0,.02475,.0066,.0231,0.0*
1,1,.006,.0066,.0231*
20,1,.006,.0066,.0231,.01237,.01897,0.0*
1,1,.006,.01237,.01897*
20,1,.006,.01237,.01897,.01485,.0132,0.0*
1,1,.006,.01485,.0132*
20,1,.006,.01485,.0132,.0132,.00742,0.0*
1,1,.006,.0132,.00742*
20,1,.006,.0132,.00742,.00908,.0033,0.0*
1,1,.006,.00908,.0033*
20,1,.006,.00908,.0033,.00412,.00165,0.0*
1,1,.006,.00412,.00165*
20,1,.006,.00412,.00165,-.00412,.00165,0.0*
1,1,.006,-.00412,.00165*
20,1,.006,-.00412,.00165,-.01155,-.00083,0.0*
1,1,.006,-.01155,-.00083*
20,1,.006,-.01155,-.00083,-.0165,-.00578,0.0*
1,1,.006,-.0165,-.00578*
20,1,.006,-.0165,-.00578,-.01815,-.01155,0.0*
1,1,.006,-.01815,-.01155*
20,1,.006,-.01815,-.01155,-.0165,-.01733,0.0*
1,1,.006,-.0165,-.01733*
20,1,.006,-.0165,-.01733,-.01237,-.02145,0.0*
1,1,.006,-.01237,-.02145*
20,1,.006,-.01237,-.02145,-.00577,-.02393,0.0*
1,1,.006,-.00577,-.02393*
20,1,.006,-.00577,-.02393,0.0,-.02475,0.0*
1,1,.006,0.0,-.02475*
%
%ADD21MACRO21*%
%AMMACRO15*
1,1,.006,.005,0.0*
20,1,.006,.005,0.0,-.005,0.0,0.0*
1,1,.006,-.005,0.0*
1,1,.006,0.0,.005*
20,1,.006,0.0,.005,0.0,-.005,0.0*
1,1,.006,0.0,-.005*
1,1,.006,.0025,0.0*
20,1,.006,.0025,0.0,.0025,.005,0.0*
1,1,.006,.0025,.005*
20,1,.006,.0025,.005,.0015,.004,0.0*
1,1,.006,.0015,.004*
1,1,.006,.0015,0.0*
20,1,.006,.0015,0.0,.0035,0.0,0.0*
1,1,.006,.0035,0.0*
%
%ADD15MACRO15*%
%AMMACRO11*
1,1,.006,.006,.006*
20,1,.006,.006,.006,.006,-.006,0.0*
1,1,.006,.006,-.006*
20,1,.006,.006,-.006,-.006,-.006,0.0*
1,1,.006,-.006,-.006*
20,1,.006,-.006,-.006,-.006,.006,0.0*
1,1,.006,-.006,.006*
20,1,.006,-.006,.006,.006,.006,0.0*
1,1,.006,.006,.006*
1,1,.006,-.0019,.002*
20,1,.006,-.0019,.002,-.0013,.0026,0.0*
1,1,.006,-.0013,.0026*
20,1,.006,-.0013,.0026,-.0006,.0029,0.0*
1,1,.006,-.0006,.0029*
20,1,.006,-.0006,.0029,.0002,.003,0.0*
1,1,.006,.0002,.003*
20,1,.006,.0002,.003,.0012,.0028,0.0*
1,1,.006,.0012,.0028*
20,1,.006,.0012,.0028,.0019,.0023,0.0*
1,1,.006,.0019,.0023*
20,1,.006,.0019,.0023,.0021,.0017,0.0*
1,1,.006,.0021,.0017*
20,1,.006,.0021,.0017,.002,.0011,0.0*
1,1,.006,.002,.0011*
20,1,.006,.002,.0011,.0016,.0006,0.0*
1,1,.006,.0016,.0006*
20,1,.006,.0016,.0006,-.0004,-.0004,0.0*
1,1,.006,-.0004,-.0004*
20,1,.006,-.0004,-.0004,-.0013,-.0011,0.0*
1,1,.006,-.0013,-.0011*
20,1,.006,-.0013,-.0011,-.0019,-.0021,0.0*
1,1,.006,-.0019,-.0021*
20,1,.006,-.0019,-.0021,-.0021,-.003,0.0*
1,1,.006,-.0021,-.003*
20,1,.006,-.0021,-.003,.0021,-.003,0.0*
1,1,.006,.0021,-.003*
%
%ADD11MACRO11*%
%AMMACRO10*
1,1,.006,.01866,.00467*
20,1,.006,.01866,.00467,.028,.01167,0.0*
1,1,.006,.028,.01167*
20,1,.006,.028,.01167,.035,.02333,0.0*
1,1,.006,.035,.02333*
20,1,.006,.035,.02333,.03967,.03967,0.0*
1,1,.006,.03967,.03967*
20,1,.006,.03967,.03967,.035,.05367,0.0*
1,1,.006,.035,.05367*
20,1,.006,.035,.05367,.02567,.063,0.0*
1,1,.006,.02567,.063*
20,1,.006,.02567,.063,.00933,.07,0.0*
1,1,.006,.00933,.07*
20,1,.006,.00933,.07,-.05367,.07,0.0*
1,1,.006,-.05367,.07*
20,1,.006,-.05367,.07,-.05367,-.07,0.0*
1,1,.006,-.05367,-.07*
20,1,.006,-.05367,-.07,.02333,-.07,0.0*
1,1,.006,.02333,-.07*
20,1,.006,.02333,-.07,.03967,-.06067,0.0*
1,1,.006,.03967,-.06067*
20,1,.006,.03967,-.06067,.049,-.04667,0.0*
1,1,.006,.049,-.04667*
20,1,.006,.049,-.04667,.05367,-.03033,0.0*
1,1,.006,.05367,-.03033*
20,1,.006,.05367,-.03033,.049,-.014,0.0*
1,1,.006,.049,-.014*
20,1,.006,.049,-.014,.035,0.0,0.0*
1,1,.006,.035,0.0*
20,1,.006,.035,0.0,.01866,.00467,0.0*
1,1,.006,.01866,.00467*
20,1,.006,.01866,.00467,-.05367,.00467,0.0*
1,1,.006,-.05367,.00467*
%
%ADD10MACRO10*%
%AMMACRO17*
1,1,.006,.007249,-.0175*
20,1,.006,.007249,-.0175,-.007249,-.0175,0.0*
1,1,.006,-.007249,-.0175*
20,1,.006,-.007249,-.0175,-.0175,-.007249,0.0*
1,1,.006,-.0175,-.007249*
20,1,.006,-.0175,-.007249,-.0175,.007249,0.0*
1,1,.006,-.0175,.007249*
20,1,.006,-.0175,.007249,-.007249,.0175,0.0*
1,1,.006,-.007249,.0175*
20,1,.006,-.007249,.0175,.007249,.0175,0.0*
1,1,.006,.007249,.0175*
20,1,.006,.007249,.0175,.0175,.007249,0.0*
1,1,.006,.0175,.007249*
20,1,.006,.0175,.007249,.0175,-.007249,0.0*
1,1,.006,.0175,-.007249*
20,1,.006,.0175,-.007249,.007249,-.0175,0.0*
1,1,.006,.007249,-.0175*
1,1,.006,-.00642,-.00613*
20,1,.006,-.00642,-.00613,-.00467,-.00758,0.0*
1,1,.006,-.00467,-.00758*
20,1,.006,-.00467,-.00758,-.00263,-.00846,0.0*
1,1,.006,-.00263,-.00846*
20,1,.006,-.00263,-.00846,0.0,-.00875,0.0*
1,1,.006,0.0,-.00875*
20,1,.006,0.0,-.00875,.00263,-.00817,0.0*
1,1,.006,.00263,-.00817*
20,1,.006,.00263,-.00817,.00467,-.007,0.0*
1,1,.006,.00467,-.007*
20,1,.006,.00467,-.007,.00613,-.00496,0.0*
1,1,.006,.00613,-.00496*
20,1,.006,.00613,-.00496,.00642,-.00263,0.0*
1,1,.006,.00642,-.00263*
20,1,.006,.00642,-.00263,.00583,-.00029,0.0*
1,1,.006,.00583,-.00029*
20,1,.006,.00583,-.00029,.00437,.00117,0.0*
1,1,.006,.00437,.00117*
20,1,.006,.00437,.00117,.00233,.00233,0.0*
1,1,.006,.00233,.00233*
20,1,.006,.00233,.00233,.00029,.00262,0.0*
1,1,.006,.00029,.00262*
20,1,.006,.00029,.00262,-.00175,.00233,0.0*
1,1,.006,-.00175,.00233*
20,1,.006,-.00175,.00233,-.00437,.00117,0.0*
1,1,.006,-.00437,.00117*
20,1,.006,-.00437,.00117,-.0035,.00875,0.0*
1,1,.006,-.0035,.00875*
20,1,.006,-.0035,.00875,.00437,.00875,0.0*
1,1,.006,.00437,.00875*
%
%ADD17MACRO17*%
%AMMACRO19*
1,1,.006,.0195,0.0*
20,1,.006,.0195,0.0,0.0,-.0195,0.0*
1,1,.006,0.0,-.0195*
20,1,.006,0.0,-.0195,-.0195,0.0,0.0*
1,1,.006,-.0195,0.0*
20,1,.006,-.0195,0.0,0.0,.0195,0.0*
1,1,.006,0.0,.0195*
20,1,.006,0.0,.0195,.0195,0.0,0.0*
1,1,.006,.0195,0.0*
1,1,.006,-.00618,-.00163*
20,1,.006,-.00618,-.00163,-.0039,.00065,0.0*
1,1,.006,-.0039,.00065*
20,1,.006,-.0039,.00065,-.00195,.00195,0.0*
1,1,.006,-.00195,.00195*
20,1,.006,-.00195,.00195,.00065,.0026,0.0*
1,1,.006,.00065,.0026*
20,1,.006,.00065,.0026,.00293,.00195,0.0*
1,1,.006,.00293,.00195*
20,1,.006,.00293,.00195,.00455,.00065,0.0*
1,1,.006,.00455,.00065*
20,1,.006,.00455,.00065,.00585,-.0013,0.0*
1,1,.006,.00585,-.0013*
20,1,.006,.00585,-.0013,.00618,-.00358,0.0*
1,1,.006,.00618,-.00358*
20,1,.006,.00618,-.00358,.00585,-.00553,0.0*
1,1,.006,.00585,-.00553*
20,1,.006,.00585,-.00553,.00455,-.00748,0.0*
1,1,.006,.00455,-.00748*
20,1,.006,.00455,-.00748,.0026,-.0091,0.0*
1,1,.006,.0026,-.0091*
20,1,.006,.0026,-.0091,.00033,-.00975,0.0*
1,1,.006,.00033,-.00975*
20,1,.006,.00033,-.00975,-.00227,-.0091,0.0*
1,1,.006,-.00227,-.0091*
20,1,.006,-.00227,-.0091,-.00455,-.00715,0.0*
1,1,.006,-.00455,-.00715*
20,1,.006,-.00455,-.00715,-.00585,-.00422,0.0*
1,1,.006,-.00585,-.00422*
20,1,.006,-.00585,-.00422,-.00618,-.00098,0.0*
1,1,.006,-.00618,-.00098*
20,1,.006,-.00618,-.00098,-.00553,.00325,0.0*
1,1,.006,-.00553,.00325*
20,1,.006,-.00553,.00325,-.00455,.00553,0.0*
1,1,.006,-.00455,.00553*
20,1,.006,-.00455,.00553,-.00293,.0078,0.0*
1,1,.006,-.00293,.0078*
20,1,.006,-.00293,.0078,-.00065,.00943,0.0*
1,1,.006,-.00065,.00943*
20,1,.006,-.00065,.00943,.00162,.00975,0.0*
1,1,.006,.00162,.00975*
20,1,.006,.00162,.00975,.0039,.0091,0.0*
1,1,.006,.0039,.0091*
20,1,.006,.0039,.0091,.00553,.00747,0.0*
1,1,.006,.00553,.00747*
%
%ADD19MACRO19*%
%AMMACRO12*
1,1,.006,.05793,.06583*
20,1,.006,.05793,.06583,.04213,.07373,0.0*
1,1,.006,.04213,.07373*
20,1,.006,.04213,.07373,.0237,.079,0.0*
1,1,.006,.0237,.079*
20,1,.006,.0237,.079,.00264,.079,0.0*
1,1,.006,.00264,.079*
20,1,.006,.00264,.079,-.02107,.0711,0.0*
1,1,.006,-.02107,.0711*
20,1,.006,-.02107,.0711,-.0395,.05793,0.0*
1,1,.006,-.0395,.05793*
20,1,.006,-.0395,.05793,-.05267,.04213,0.0*
1,1,.006,-.05267,.04213*
20,1,.006,-.05267,.04213,-.0632,.0158,0.0*
1,1,.006,-.0632,.0158*
20,1,.006,-.0632,.0158,-.06584,-.0079,0.0*
1,1,.006,-.06584,-.0079*
20,1,.006,-.06584,-.0079,-.06057,-.0316,0.0*
1,1,.006,-.06057,-.0316*
20,1,.006,-.06057,-.0316,-.05267,-.0474,0.0*
1,1,.006,-.05267,-.0474*
20,1,.006,-.05267,-.0474,-.03687,-.0632,0.0*
1,1,.006,-.03687,-.0632*
20,1,.006,-.03687,-.0632,-.01843,-.07373,0.0*
1,1,.006,-.01843,-.07373*
20,1,.006,-.01843,-.07373,0.0,-.079,0.0*
1,1,.006,0.0,-.079*
20,1,.006,0.0,-.079,.01843,-.079,0.0*
1,1,.006,.01843,-.079*
20,1,.006,.01843,-.079,.03687,-.07373,0.0*
1,1,.006,.03687,-.07373*
20,1,.006,.03687,-.07373,.05267,-.06584,0.0*
1,1,.006,.05267,-.06584*
20,1,.006,.05267,-.06584,.06584,-.05531,0.0*
1,1,.006,.06584,-.05531*
%
%ADD12MACRO12*%
%AMMACRO24*
1,1,.006,-.07223,-.0985*
20,1,.006,-.07223,-.0985,-.07223,.0985,0.0*
1,1,.006,-.07223,.0985*
20,1,.006,-.07223,.0985,-.00657,.0985,0.0*
1,1,.006,-.00657,.0985*
20,1,.006,-.00657,.0985,.0197,.08865,0.0*
1,1,.006,.0197,.08865*
20,1,.006,.0197,.08865,.0394,.07552,0.0*
1,1,.006,.0394,.07552*
20,1,.006,.0394,.07552,.05582,.05582,0.0*
1,1,.006,.05582,.05582*
20,1,.006,.05582,.05582,.06895,.03283,0.0*
1,1,.006,.06895,.03283*
20,1,.006,.06895,.03283,.07223,0.0,0.0*
1,1,.006,.07223,0.0*
20,1,.006,.07223,0.0,.06895,-.03284,0.0*
1,1,.006,.06895,-.03284*
20,1,.006,.06895,-.03284,.05582,-.05582,0.0*
1,1,.006,.05582,-.05582*
20,1,.006,.05582,-.05582,.0394,-.07552,0.0*
1,1,.006,.0394,-.07552*
20,1,.006,.0394,-.07552,.0197,-.08865,0.0*
1,1,.006,.0197,-.08865*
20,1,.006,.0197,-.08865,-.00657,-.0985,0.0*
1,1,.006,-.00657,-.0985*
20,1,.006,-.00657,-.0985,-.07223,-.0985,0.0*
1,1,.006,-.07223,-.0985*
%
%ADD24MACRO24*%
%AMMACRO14*
1,1,.006,-.03292,-.0395*
20,1,.006,-.03292,-.0395,0.0,.0395,0.0*
1,1,.006,0.0,.0395*
20,1,.006,0.0,.0395,.03292,-.0395,0.0*
1,1,.006,.03292,-.0395*
1,1,.006,.02107,-.01185*
20,1,.006,.02107,-.01185,-.02107,-.01185,0.0*
1,1,.006,-.02107,-.01185*
%
%ADD14MACRO14*%
%AMMACRO20*
1,1,.006,.031,0.0*
20,1,.006,.031,0.0,.030529,-.005383,0.0*
1,1,.006,.030529,-.005383*
20,1,.006,.030529,-.005383,.02913,-.010603,0.0*
1,1,.006,.02913,-.010603*
20,1,.006,.02913,-.010603,.026847,-.0155,0.0*
1,1,.006,.026847,-.0155*
20,1,.006,.026847,-.0155,.023747,-.019926,0.0*
1,1,.006,.023747,-.019926*
20,1,.006,.023747,-.019926,.019926,-.023747,0.0*
1,1,.006,.019926,-.023747*
20,1,.006,.019926,-.023747,.0155,-.026847,0.0*
1,1,.006,.0155,-.026847*
20,1,.006,.0155,-.026847,.010603,-.02913,0.0*
1,1,.006,.010603,-.02913*
20,1,.006,.010603,-.02913,.005383,-.030529,0.0*
1,1,.006,.005383,-.030529*
20,1,.006,.005383,-.030529,0.0,-.031,0.0*
1,1,.006,0.0,-.031*
20,1,.006,0.0,-.031,-.005383,-.030529,0.0*
1,1,.006,-.005383,-.030529*
20,1,.006,-.005383,-.030529,-.010603,-.02913,0.0*
1,1,.006,-.010603,-.02913*
20,1,.006,-.010603,-.02913,-.0155,-.026847,0.0*
1,1,.006,-.0155,-.026847*
20,1,.006,-.0155,-.026847,-.019926,-.023747,0.0*
1,1,.006,-.019926,-.023747*
20,1,.006,-.019926,-.023747,-.023747,-.019926,0.0*
1,1,.006,-.023747,-.019926*
20,1,.006,-.023747,-.019926,-.026847,-.0155,0.0*
1,1,.006,-.026847,-.0155*
20,1,.006,-.026847,-.0155,-.02913,-.010603,0.0*
1,1,.006,-.02913,-.010603*
20,1,.006,-.02913,-.010603,-.030529,-.005383,0.0*
1,1,.006,-.030529,-.005383*
20,1,.006,-.030529,-.005383,-.031,0.0,0.0*
1,1,.006,-.031,0.0*
20,1,.006,-.031,0.0,-.030529,.005383,0.0*
1,1,.006,-.030529,.005383*
20,1,.006,-.030529,.005383,-.02913,.010603,0.0*
1,1,.006,-.02913,.010603*
20,1,.006,-.02913,.010603,-.026847,.0155,0.0*
1,1,.006,-.026847,.0155*
20,1,.006,-.026847,.0155,-.023747,.019926,0.0*
1,1,.006,-.023747,.019926*
20,1,.006,-.023747,.019926,-.019926,.023747,0.0*
1,1,.006,-.019926,.023747*
20,1,.006,-.019926,.023747,-.0155,.026847,0.0*
1,1,.006,-.0155,.026847*
20,1,.006,-.0155,.026847,-.010603,.02913,0.0*
1,1,.006,-.010603,.02913*
20,1,.006,-.010603,.02913,-.005383,.030529,0.0*
1,1,.006,-.005383,.030529*
20,1,.006,-.005383,.030529,0.0,.031,0.0*
1,1,.006,0.0,.031*
20,1,.006,0.0,.031,.005383,.030529,0.0*
1,1,.006,.005383,.030529*
20,1,.006,.005383,.030529,.010603,.02913,0.0*
1,1,.006,.010603,.02913*
20,1,.006,.010603,.02913,.0155,.026847,0.0*
1,1,.006,.0155,.026847*
20,1,.006,.0155,.026847,.019926,.023747,0.0*
1,1,.006,.019926,.023747*
20,1,.006,.019926,.023747,.023747,.019926,0.0*
1,1,.006,.023747,.019926*
20,1,.006,.023747,.019926,.026847,.0155,0.0*
1,1,.006,.026847,.0155*
20,1,.006,.026847,.0155,.02913,.010603,0.0*
1,1,.006,.02913,.010603*
20,1,.006,.02913,.010603,.030529,.005383,0.0*
1,1,.006,.030529,.005383*
20,1,.006,.030529,.005383,.031,0.0,0.0*
1,1,.006,.031,0.0*
1,1,.006,-.0155,-.0155*
20,1,.006,-.0155,-.0155,-.0155,.0155,0.0*
1,1,.006,-.0155,.0155*
20,1,.006,-.0155,.0155,-.0217,.0093,0.0*
1,1,.006,-.0217,.0093*
1,1,.006,-.0217,-.0155*
20,1,.006,-.0217,-.0155,-.0093,-.0155,0.0*
1,1,.006,-.0093,-.0155*
1,1,.006,.01551,-.0155*
20,1,.006,.01551,-.0155,.01551,.0155,0.0*
1,1,.006,.01551,.0155*
20,1,.006,.01551,.0155,.00931,.0093,0.0*
1,1,.006,.00931,.0093*
1,1,.006,.00931,-.0155*
20,1,.006,.00931,-.0155,.02171,-.0155,0.0*
1,1,.006,.02171,-.0155*
%
%ADD20MACRO20*%
%AMMACRO22*
1,1,.006,.0305,.0305*
20,1,.006,.0305,.0305,.0305,-.0305,0.0*
1,1,.006,.0305,-.0305*
20,1,.006,.0305,-.0305,-.0305,-.0305,0.0*
1,1,.006,-.0305,-.0305*
20,1,.006,-.0305,-.0305,-.0305,.0305,0.0*
1,1,.006,-.0305,.0305*
20,1,.006,-.0305,.0305,.0305,.0305,0.0*
1,1,.006,.0305,.0305*
1,1,.006,-.01525,-.01525*
20,1,.006,-.01525,-.01525,-.01525,.01525,0.0*
1,1,.006,-.01525,.01525*
20,1,.006,-.01525,.01525,-.02135,.00915,0.0*
1,1,.006,-.02135,.00915*
1,1,.006,-.02135,-.01525*
20,1,.006,-.02135,-.01525,-.00915,-.01525,0.0*
1,1,.006,-.00915,-.01525*
1,1,.006,.01526,.01525*
20,1,.006,.01526,.01525,.01119,.01423,0.0*
1,1,.006,.01119,.01423*
20,1,.006,.01119,.01423,.00814,.01169,0.0*
1,1,.006,.00814,.01169*
20,1,.006,.00814,.01169,.00611,.00864,0.0*
1,1,.006,.00611,.00864*
20,1,.006,.00611,.00864,.00458,.00457,0.0*
1,1,.006,.00458,.00457*
20,1,.006,.00458,.00457,.00408,0.0,0.0*
1,1,.006,.00408,0.0*
20,1,.006,.00408,0.0,.00458,-.00458,0.0*
1,1,.006,.00458,-.00458*
20,1,.006,.00458,-.00458,.00611,-.00864,0.0*
1,1,.006,.00611,-.00864*
20,1,.006,.00611,-.00864,.00814,-.01169,0.0*
1,1,.006,.00814,-.01169*
20,1,.006,.00814,-.01169,.01119,-.01423,0.0*
1,1,.006,.01119,-.01423*
20,1,.006,.01119,-.01423,.01526,-.01525,0.0*
1,1,.006,.01526,-.01525*
20,1,.006,.01526,-.01525,.01933,-.01423,0.0*
1,1,.006,.01933,-.01423*
20,1,.006,.01933,-.01423,.02238,-.01169,0.0*
1,1,.006,.02238,-.01169*
20,1,.006,.02238,-.01169,.02441,-.00864,0.0*
1,1,.006,.02441,-.00864*
20,1,.006,.02441,-.00864,.02594,-.00458,0.0*
1,1,.006,.02594,-.00458*
20,1,.006,.02594,-.00458,.02644,0.0,0.0*
1,1,.006,.02644,0.0*
20,1,.006,.02644,0.0,.02594,.00457,0.0*
1,1,.006,.02594,.00457*
20,1,.006,.02594,.00457,.02441,.00864,0.0*
1,1,.006,.02441,.00864*
20,1,.006,.02441,.00864,.02238,.01169,0.0*
1,1,.006,.02238,.01169*
20,1,.006,.02238,.01169,.01933,.01423,0.0*
1,1,.006,.01933,.01423*
20,1,.006,.01933,.01423,.01526,.01525,0.0*
1,1,.006,.01526,.01525*
%
%ADD22MACRO22*%
%AMMACRO16*
1,1,.006,0.0,.016*
20,1,.006,0.0,.016,-.013856,.008,0.0*
1,1,.006,-.013856,.008*
20,1,.006,-.013856,.008,-.013856,-.008,0.0*
1,1,.006,-.013856,-.008*
20,1,.006,-.013856,-.008,0.0,-.016,0.0*
1,1,.006,0.0,-.016*
20,1,.006,0.0,-.016,.013856,-.008,0.0*
1,1,.006,.013856,-.008*
20,1,.006,.013856,-.008,.013856,.008,0.0*
1,1,.006,.013856,.008*
20,1,.006,.013856,.008,0.0,.016,0.0*
1,1,.006,0.0,.016*
1,1,.006,.0032,-.008*
20,1,.006,.0032,-.008,.0032,.008,0.0*
1,1,.006,.0032,.008*
20,1,.006,.0032,.008,-.00667,-.00347,0.0*
1,1,.006,-.00667,-.00347*
20,1,.006,-.00667,-.00347,.00667,-.00347,0.0*
1,1,.006,.00667,-.00347*
%
%ADD16MACRO16*%
%AMMACRO13*
1,1,.006,.008,0.0*
20,1,.006,.008,0.0,.004,.006928,0.0*
1,1,.006,.004,.006928*
20,1,.006,.004,.006928,-.004,.006928,0.0*
1,1,.006,-.004,.006928*
20,1,.006,-.004,.006928,-.008,0.0,0.0*
1,1,.006,-.008,0.0*
20,1,.006,-.008,0.0,-.004,-.006928,0.0*
1,1,.006,-.004,-.006928*
20,1,.006,-.004,-.006928,.004,-.006928,0.0*
1,1,.006,.004,-.006928*
20,1,.006,.004,-.006928,.008,0.0,0.0*
1,1,.006,.008,0.0*
1,1,.006,-.00293,-.0024*
20,1,.006,-.00293,-.0024,-.00213,-.00333,0.0*
1,1,.006,-.00213,-.00333*
20,1,.006,-.00213,-.00333,-.00107,-.00387,0.0*
1,1,.006,-.00107,-.00387*
20,1,.006,-.00107,-.00387,.00013,-.004,0.0*
1,1,.006,.00013,-.004*
20,1,.006,.00013,-.004,.0012,-.00387,0.0*
1,1,.006,.0012,-.00387*
20,1,.006,.0012,-.00387,.00227,-.0032,0.0*
1,1,.006,.00227,-.0032*
20,1,.006,.00227,-.0032,.00293,-.0024,0.0*
1,1,.006,.00293,-.0024*
20,1,.006,.00293,-.0024,.00307,-.0016,0.0*
1,1,.006,.00307,-.0016*
20,1,.006,.00307,-.0016,.0028,-.00067,0.0*
1,1,.006,.0028,-.00067*
20,1,.006,.0028,-.00067,.00187,0.0,0.0*
1,1,.006,.00187,0.0*
20,1,.006,.00187,0.0,.00093,.00027,0.0*
1,1,.006,.00093,.00027*
20,1,.006,.00093,.00027,-.00027,.00027,0.0*
1,1,.006,-.00027,.00027*
1,1,.006,.00093,.00027*
20,1,.006,.00093,.00027,.00173,.00067,0.0*
1,1,.006,.00173,.00067*
20,1,.006,.00173,.00067,.0024,.00133,0.0*
1,1,.006,.0024,.00133*
20,1,.006,.0024,.00133,.00267,.00213,0.0*
1,1,.006,.00267,.00213*
20,1,.006,.00267,.00213,.0024,.00293,0.0*
1,1,.006,.0024,.00293*
20,1,.006,.0024,.00293,.00173,.0036,0.0*
1,1,.006,.00173,.0036*
20,1,.006,.00173,.0036,.00053,.004,0.0*
1,1,.006,.00053,.004*
20,1,.006,.00053,.004,-.00067,.00387,0.0*
1,1,.006,-.00067,.00387*
20,1,.006,-.00067,.00387,-.00187,.00333,0.0*
1,1,.006,-.00187,.00333*
%
%ADD13MACRO13*%
%AMMACRO23*
1,1,.006,0.0,.0225*
20,1,.006,0.0,.0225,.0225,-.0225,0.0*
1,1,.006,.0225,-.0225*
20,1,.006,.0225,-.0225,-.0225,-.0225,0.0*
1,1,.006,-.0225,-.0225*
20,1,.006,-.0225,-.0225,0.0,.0225,0.0*
1,1,.006,0.0,.0225*
1,1,.006,-.00075,-.01125*
20,1,.006,-.00075,-.01125,0.0,-.00638,0.0*
1,1,.006,0.0,-.00638*
20,1,.006,0.0,-.00638,.00113,-.00225,0.0*
1,1,.006,.00113,-.00225*
20,1,.006,.00113,-.00225,.00262,.0015,0.0*
1,1,.006,.00262,.0015*
20,1,.006,.00262,.0015,.0045,.00562,0.0*
1,1,.006,.0045,.00562*
20,1,.006,.0045,.00562,.0075,.01125,0.0*
1,1,.006,.0075,.01125*
20,1,.006,.0075,.01125,-.0075,.01125,0.0*
1,1,.006,-.0075,.01125*
%
%ADD23MACRO23*%
%AMMACRO18*
1,1,.006,-.0985,0.0*
20,1,.006,-.0985,0.0,-.097004,.017104,0.0*
1,1,.006,-.097004,.017104*
20,1,.006,-.097004,.017104,-.09256,.033689,0.0*
1,1,.006,-.09256,.033689*
20,1,.006,-.09256,.033689,-.085304,.04925,0.0*
1,1,.006,-.085304,.04925*
20,1,.006,-.085304,.04925,-.075455,.063315,0.0*
1,1,.006,-.075455,.063315*
20,1,.006,-.075455,.063315,-.063315,.075455,0.0*
1,1,.006,-.063315,.075455*
20,1,.006,-.063315,.075455,-.04925,.085304,0.0*
1,1,.006,-.04925,.085304*
20,1,.006,-.04925,.085304,-.033689,.09256,0.0*
1,1,.006,-.033689,.09256*
20,1,.006,-.033689,.09256,-.017104,.097004,0.0*
1,1,.006,-.017104,.097004*
20,1,.006,-.017104,.097004,0.0,.0985,0.0*
1,1,.006,0.0,.0985*
20,1,.006,0.0,.0985,.017104,.097004,0.0*
1,1,.006,.017104,.097004*
20,1,.006,.017104,.097004,.033689,.09256,0.0*
1,1,.006,.033689,.09256*
20,1,.006,.033689,.09256,.04925,.085304,0.0*
1,1,.006,.04925,.085304*
20,1,.006,.04925,.085304,.063315,.075455,0.0*
1,1,.006,.063315,.075455*
20,1,.006,.063315,.075455,.075455,.063315,0.0*
1,1,.006,.075455,.063315*
20,1,.006,.075455,.063315,.085304,.04925,0.0*
1,1,.006,.085304,.04925*
20,1,.006,.085304,.04925,.09256,.033689,0.0*
1,1,.006,.09256,.033689*
20,1,.006,.09256,.033689,.097004,.017104,0.0*
1,1,.006,.097004,.017104*
20,1,.006,.097004,.017104,.0985,0.0,0.0*
1,1,.006,.0985,0.0*
20,1,.006,.0985,0.0,.0985,0.0,0.0*
1,1,.006,.0985,0.0*
20,1,.006,.0985,0.0,.097004,-.017104,0.0*
1,1,.006,.097004,-.017104*
20,1,.006,.097004,-.017104,.09256,-.033689,0.0*
1,1,.006,.09256,-.033689*
20,1,.006,.09256,-.033689,.085304,-.04925,0.0*
1,1,.006,.085304,-.04925*
20,1,.006,.085304,-.04925,.075455,-.063315,0.0*
1,1,.006,.075455,-.063315*
20,1,.006,.075455,-.063315,.063315,-.075455,0.0*
1,1,.006,.063315,-.075455*
20,1,.006,.063315,-.075455,.04925,-.085304,0.0*
1,1,.006,.04925,-.085304*
20,1,.006,.04925,-.085304,.033689,-.09256,0.0*
1,1,.006,.033689,-.09256*
20,1,.006,.033689,-.09256,.017104,-.097004,0.0*
1,1,.006,.017104,-.097004*
20,1,.006,.017104,-.097004,0.0,-.0985,0.0*
1,1,.006,0.0,-.0985*
20,1,.006,0.0,-.0985,-.017104,-.097004,0.0*
1,1,.006,-.017104,-.097004*
20,1,.006,-.017104,-.097004,-.033689,-.09256,0.0*
1,1,.006,-.033689,-.09256*
20,1,.006,-.033689,-.09256,-.04925,-.085304,0.0*
1,1,.006,-.04925,-.085304*
20,1,.006,-.04925,-.085304,-.063315,-.075455,0.0*
1,1,.006,-.063315,-.075455*
20,1,.006,-.063315,-.075455,-.075455,-.063315,0.0*
1,1,.006,-.075455,-.063315*
20,1,.006,-.075455,-.063315,-.085304,-.04925,0.0*
1,1,.006,-.085304,-.04925*
20,1,.006,-.085304,-.04925,-.09256,-.033689,0.0*
1,1,.006,-.09256,-.033689*
20,1,.006,-.09256,-.033689,-.097004,-.017104,0.0*
1,1,.006,-.097004,-.017104*
20,1,.006,-.097004,-.017104,-.0985,0.0,0.0*
1,1,.006,-.0985,0.0*
20,1,.006,-.0985,0.0,-.0985,0.0,0.0*
1,1,.006,-.0985,0.0*
1,1,.006,-.02791,-.03776*
20,1,.006,-.02791,-.03776,-.01642,-.04597,0.0*
1,1,.006,-.01642,-.04597*
20,1,.006,-.01642,-.04597,-.00328,-.04925,0.0*
1,1,.006,-.00328,-.04925*
20,1,.006,-.00328,-.04925,.00985,-.04597,0.0*
1,1,.006,.00985,-.04597*
20,1,.006,.00985,-.04597,.02134,-.03612,0.0*
1,1,.006,.02134,-.03612*
20,1,.006,.02134,-.03612,.02955,-.02134,0.0*
1,1,.006,.02955,-.02134*
20,1,.006,.02955,-.02134,.03283,-.00657,0.0*
1,1,.006,.03283,-.00657*
20,1,.006,.03283,-.00657,.03283,.01149,0.0*
1,1,.006,.03283,.01149*
20,1,.006,.03283,.01149,.02955,.02627,0.0*
1,1,.006,.02955,.02627*
20,1,.006,.02955,.02627,.02134,.0394,0.0*
1,1,.006,.02134,.0394*
20,1,.006,.02134,.0394,.01149,.04597,0.0*
1,1,.006,.01149,.04597*
20,1,.006,.01149,.04597,0.0,.04925,0.0*
1,1,.006,0.0,.04925*
20,1,.006,0.0,.04925,-.01314,.04597,0.0*
1,1,.006,-.01314,.04597*
20,1,.006,-.01314,.04597,-.02298,.0394,0.0*
1,1,.006,-.02298,.0394*
20,1,.006,-.02298,.0394,-.02955,.02955,0.0*
1,1,.006,-.02955,.02955*
20,1,.006,-.02955,.02955,-.03283,.01641,0.0*
1,1,.006,-.03283,.01641*
20,1,.006,-.03283,.01641,-.02955,.00493,0.0*
1,1,.006,-.02955,.00493*
20,1,.006,-.02955,.00493,-.02134,-.00657,0.0*
1,1,.006,-.02134,-.00657*
20,1,.006,-.02134,-.00657,-.01149,-.01314,0.0*
1,1,.006,-.01149,-.01314*
20,1,.006,-.01149,-.01314,0.0,-.01478,0.0*
1,1,.006,0.0,-.01478*
20,1,.006,0.0,-.01478,.01313,-.01149,0.0*
1,1,.006,.01313,-.01149*
20,1,.006,.01313,-.01149,.02298,-.00328,0.0*
1,1,.006,.02298,-.00328*
20,1,.006,.02298,-.00328,.03283,.01149,0.0*
1,1,.006,.03283,.01149*
%
%ADD18MACRO18*%
%ADD25C,.02*%
%ADD26C,.006*%
G75*
%LPD*%
G75*
G54D10*
X-1011811Y-15748D03*
Y940945D03*
X775591Y-15748D03*
Y940944D03*
X932850Y264595D03*
G54D20*
X54724Y557087D03*
Y620079D03*
Y675197D03*
Y738189D03*
X144843Y798779D03*
Y874449D03*
X932850Y323695D03*
G54D11*
X-138100Y222300D03*
Y241300D03*
Y260300D03*
Y279300D03*
Y298300D03*
Y317300D03*
Y336300D03*
X-70100Y222300D03*
X-87100D03*
X-104100D03*
X-121100D03*
X-70100Y241300D03*
X-87100D03*
X-104100D03*
X-121100D03*
X-70100Y260300D03*
X-87100D03*
X-104100D03*
X-121100D03*
X-70100Y279300D03*
X-87100D03*
X-104100D03*
X-121100D03*
X-70100Y298300D03*
X-87100D03*
X-104100D03*
X-121100D03*
X-70100Y317300D03*
X-87100D03*
X-104100D03*
X-121100D03*
X-70100Y336300D03*
X-87100D03*
X-104100D03*
X-121100D03*
X-2100Y222300D03*
X-19100D03*
X-36100D03*
X-53100D03*
X-2100Y241300D03*
X-19100D03*
X-36100D03*
X-53100D03*
X-2100Y260300D03*
X-19100D03*
X-36300Y260000D03*
X-53100Y260300D03*
X9243Y334400D03*
X-1900Y288300D03*
X-49400Y284500D03*
X-19600Y279500D03*
X-36100Y279300D03*
X-2100Y298300D03*
X-19100D03*
X-36100D03*
X-53100D03*
X-2100Y317300D03*
X-19100D03*
X-36100D03*
X-53100D03*
X-2100Y336300D03*
X-19100D03*
X-36100D03*
X-53100D03*
X-1600Y413600D03*
Y394600D03*
Y375600D03*
Y356600D03*
X-52600Y413600D03*
X-35600D03*
X-18600D03*
X-52600Y394600D03*
X-35600D03*
X-18600D03*
X-52600Y375600D03*
X-35600D03*
X-18600D03*
X-52600Y356600D03*
X-35600D03*
X-18600D03*
X-19400Y483400D03*
X-2400D03*
X-36400D03*
X-53400D03*
X-1500Y470300D03*
Y451300D03*
Y432300D03*
X-52500Y470300D03*
X-35500D03*
X-18500D03*
X-52500Y451300D03*
X-35500D03*
X-18500D03*
X-52500Y432300D03*
X-35500D03*
X-18500D03*
X8788Y453864D03*
X-19400Y502400D03*
X-2400D03*
X-36400D03*
X-53400D03*
X63400Y89300D03*
X51900Y83600D03*
X43980Y86200D03*
X68000Y87750D03*
X42700Y110500D03*
X67300Y107200D03*
X63100Y107300D03*
X48100Y133900D03*
X59200Y95573D03*
X51800Y93500D03*
X79600Y91500D03*
X51900Y89900D03*
X79500Y85700D03*
X77200Y95500D03*
X69800Y176800D03*
X31500Y185700D03*
X76250Y148850D03*
X70200Y199300D03*
X47900Y145500D03*
X48100Y153800D03*
X43800Y204800D03*
X38800Y194300D03*
X38700Y199700D03*
X73700D03*
X49500Y169300D03*
X61751Y181464D03*
X44100Y200600D03*
X49286Y203671D03*
X69000Y202700D03*
X77200Y189000D03*
X60200Y193550D03*
X29600Y200100D03*
X26100Y187300D03*
X39800Y172900D03*
X27800Y191100D03*
X74700Y191700D03*
X70675Y145000D03*
X60009Y255077D03*
X55624Y255132D03*
X59523Y271123D03*
X60102Y263180D03*
X55883Y263570D03*
X33400Y266400D03*
X59258Y246890D03*
X60069Y237965D03*
X64700Y215100D03*
X51600Y217000D03*
X50500Y243100D03*
X70636Y272953D03*
X79189Y235119D03*
X43900Y209000D03*
X72001Y265901D03*
X69400Y207400D03*
X76019Y222534D03*
X42507Y296616D03*
X59316Y300366D03*
X59096Y289139D03*
X59523Y281330D03*
X52257Y276649D03*
X55420Y288656D03*
X17100Y311700D03*
X43181Y278603D03*
X39563Y307968D03*
X21876Y282289D03*
X41418Y287473D03*
X61776Y367194D03*
X43345Y386857D03*
X43639Y374043D03*
X29700Y355000D03*
X27284Y358500D03*
X67527Y381818D03*
X43569Y379314D03*
X65605Y367307D03*
X51422Y473540D03*
X24315Y472668D03*
X47307Y465104D03*
X29064Y471345D03*
X55295Y479672D03*
X20715Y485712D03*
X20276Y477090D03*
X20928Y453864D03*
X21300Y468000D03*
X38800Y535700D03*
X38200Y528900D03*
X51383Y514037D03*
X63862Y512438D03*
X73542Y514340D03*
X37200Y513500D03*
X32026Y516764D03*
X60800Y505200D03*
X56121Y494271D03*
X21090Y497108D03*
X54659Y513125D03*
X67140Y511501D03*
X50893Y534434D03*
X66300Y548000D03*
X67244Y535455D03*
X72677Y528615D03*
X69220Y614992D03*
X59379Y644787D03*
X57500Y662600D03*
X47000Y645300D03*
X69911Y676938D03*
X73900Y664900D03*
X77000Y646200D03*
X72930Y645818D03*
X67257Y643668D03*
X60122Y747800D03*
X64000Y765600D03*
X47100Y746000D03*
X69217Y732676D03*
X73325Y760926D03*
X67809Y758190D03*
X65447Y711413D03*
X62066Y711051D03*
X65356Y707010D03*
X61193Y706973D03*
X73282Y778907D03*
X106300Y105900D03*
X81150Y120850D03*
X89400Y120800D03*
X85250Y120850D03*
X117500Y106200D03*
X85000Y107800D03*
X111700Y106100D03*
X89000Y107700D03*
X82400Y89500D03*
X132500Y124600D03*
X83800Y188800D03*
X111482Y202800D03*
X113815Y194333D03*
X122400Y199000D03*
X80685Y192398D03*
X84641Y204036D03*
X79900Y148700D03*
X103300Y160900D03*
X112000Y160700D03*
X119900Y162200D03*
X125300Y162300D03*
X122100Y203300D03*
X96900Y189286D03*
X107771Y182699D03*
X145400Y161955D03*
X114700Y157000D03*
X107672Y156597D03*
X98700Y156200D03*
X122200Y156700D03*
X80207Y139965D03*
X81200Y176000D03*
X93303Y154970D03*
X144950Y177338D03*
X85713Y151540D03*
X84900Y145300D03*
X125700Y225200D03*
X121000Y225300D03*
X109400Y225400D03*
X90813D03*
X79800Y225900D03*
X87227Y242891D03*
X87263Y264658D03*
X90652Y265960D03*
X87698Y246708D03*
X94051Y265872D03*
X91230Y247047D03*
X91819Y250396D03*
X94793Y252595D03*
X98211Y252758D03*
X142933Y251431D03*
X132651Y255357D03*
X138228Y260175D03*
X124933Y270414D03*
X136427Y251413D03*
X124874Y273953D03*
X137809Y247647D03*
X135592Y257933D03*
X116566Y254205D03*
X114229Y270684D03*
X119242Y252107D03*
X112042Y275903D03*
X121685Y249741D03*
X121741Y246341D03*
X118219Y274497D03*
X122572Y258147D03*
X121599Y274869D03*
X130567Y258051D03*
X113558Y261260D03*
X111008Y242830D03*
X106381Y259865D03*
X106504Y243329D03*
X103610Y268626D03*
X102713Y242975D03*
X103003Y260260D03*
X108652Y247260D03*
X107887Y266647D03*
X101242Y265901D03*
X100415Y246679D03*
X126611Y258265D03*
X84863Y229783D03*
X134529Y264470D03*
X137190Y266587D03*
X131901Y267444D03*
X132163Y271041D03*
X137690Y273752D03*
X110610Y206436D03*
X125600Y221200D03*
X113863Y228669D03*
X102559Y228575D03*
X97885Y228339D03*
X147013Y225483D03*
X122000Y207300D03*
X94600Y206900D03*
X94548Y211258D03*
X109534Y314564D03*
X92682Y331571D03*
X140103Y328216D03*
X117460Y335158D03*
X128964Y339470D03*
X148102Y338366D03*
X119603Y285731D03*
X124478Y280855D03*
X95202Y290958D03*
X98565Y290455D03*
X102107Y290439D03*
X105603Y291092D03*
X95146Y279609D03*
X110808Y291075D03*
X98546Y279609D03*
X114915Y290203D03*
X104413Y278608D03*
X117027Y278475D03*
X148834Y284832D03*
X107750Y277953D03*
X128918Y307533D03*
X135308Y276806D03*
X139784Y276432D03*
X142241Y278783D03*
X121477Y314973D03*
X135613Y308903D03*
X95400Y383083D03*
X84200Y380000D03*
X118744Y525279D03*
X140399Y525238D03*
X129199Y525271D03*
X107103Y525057D03*
X95599Y525026D03*
X84799Y524898D03*
X90878Y585185D03*
X85654Y659044D03*
X83960Y632636D03*
X90681Y690157D03*
X90174Y678675D03*
X85600Y647837D03*
X83500Y653600D03*
Y640044D03*
X84900Y747900D03*
X93840Y699686D03*
X90814Y734451D03*
X91027Y724985D03*
X91094Y715818D03*
X84703Y758885D03*
X84182Y764879D03*
X90746Y712435D03*
X90947Y709040D03*
X91003Y705214D03*
X91130Y701741D03*
X85300Y755100D03*
X85000Y775900D03*
X84100Y769000D03*
X220131Y58163D03*
X197900Y82000D03*
X201237Y106350D03*
X210356Y99104D03*
X210680Y84396D03*
X201614Y89932D03*
X212028Y93512D03*
X212800Y125800D03*
X182400Y128300D03*
X175598Y128436D03*
X220100Y123600D03*
X166700Y128800D03*
X172200Y128300D03*
X179000D03*
X205628Y89404D03*
X152350Y131084D03*
X204849Y106438D03*
X200100Y101200D03*
X170302Y147100D03*
X158100Y166800D03*
X160311Y141680D03*
X219548Y174651D03*
X189600Y166700D03*
X189700Y170200D03*
X190018Y173586D03*
X188961Y162715D03*
X211700Y181600D03*
X208200Y153500D03*
X203900D03*
X200100Y146500D03*
Y150400D03*
X199100Y153800D03*
X194800D03*
X174339Y151172D03*
X178400Y152300D03*
X167015Y167633D03*
X163550Y179657D03*
X172645Y179104D03*
X177087Y178920D03*
X183120Y266103D03*
X183082Y271969D03*
X182853Y256107D03*
X183956Y261452D03*
X168010Y267909D03*
X219717Y211198D03*
X182177Y251208D03*
X154300Y227900D03*
X171200Y233000D03*
X185563Y245456D03*
X175064Y232857D03*
X185740Y240983D03*
X185502Y237383D03*
X152663Y272053D03*
X192284Y258847D03*
X150666Y243134D03*
X195698Y259749D03*
X196365Y256414D03*
X168324Y246397D03*
X171762Y258345D03*
X167894Y243024D03*
X167760Y239626D03*
X156800Y230500D03*
X152663Y267791D03*
X216335Y218212D03*
X196344Y237383D03*
X196078Y248183D03*
X196021Y244556D03*
X196151Y240983D03*
X151519Y250193D03*
X180641Y231683D03*
X186319Y268076D03*
X183043Y276658D03*
X183707Y289861D03*
X183653Y283162D03*
X184188Y340638D03*
X162135Y332650D03*
X185042Y286734D03*
X167051Y293752D03*
X188273Y285674D03*
X187118Y281963D03*
X163142Y294193D03*
X183466Y294017D03*
X152580Y285530D03*
X172818Y288683D03*
X216178Y411331D03*
X219144Y414536D03*
X195307Y355649D03*
X206775Y348954D03*
X173508Y348462D03*
X177715Y397471D03*
X212500Y395500D03*
X217800Y395900D03*
X200161Y416474D03*
X206142Y413945D03*
X206871Y397177D03*
X210042Y412265D03*
X175767Y380311D03*
X189073Y380379D03*
X185276Y380362D03*
X181242Y380481D03*
X197565Y380257D03*
X203379Y380312D03*
X169600Y380500D03*
X173864Y397677D03*
X213400Y434601D03*
X181980Y458681D03*
X210772Y431456D03*
X200453Y439066D03*
X203186Y451492D03*
X180445Y422567D03*
X176991Y463723D03*
X184750Y427953D03*
X208947Y443700D03*
X196803Y444462D03*
X201400Y434400D03*
X202764Y444274D03*
X190887Y424438D03*
X174500Y424100D03*
X182060Y443776D03*
X211243Y462005D03*
X203406Y454885D03*
X195038Y477148D03*
X180313Y446694D03*
X176915Y446556D03*
X195400Y452051D03*
X208632Y457048D03*
X181034Y427967D03*
X177700Y427300D03*
X184399Y525203D03*
X195499D03*
X206699D03*
X217899Y525103D03*
X162615Y525220D03*
X173537D03*
X151684Y525258D03*
X210223Y501477D03*
X213500Y503600D03*
X216300Y499600D03*
X193016Y496643D03*
X219492Y517832D03*
X219590Y740816D03*
X181642Y837321D03*
Y827853D03*
X181772Y818429D03*
X159926Y813000D03*
X201663Y827680D03*
X201142Y837191D03*
X181081Y856307D03*
X181124Y847013D03*
X200798Y846849D03*
X266700Y46900D03*
X263000Y47000D03*
X257500Y46900D03*
X253800Y47000D03*
X244900Y47300D03*
X248600Y47200D03*
X235000Y47500D03*
X238700Y47400D03*
X225231Y58420D03*
X254498Y88487D03*
X251687Y98033D03*
X261830Y81230D03*
X241101D03*
X256928Y69301D03*
X241132Y85023D03*
X259815Y94233D03*
X248000Y114500D03*
X242488Y88466D03*
X223948Y174292D03*
X246100Y151300D03*
Y155800D03*
Y160400D03*
X231049Y188760D03*
X251700Y135484D03*
X231350Y222067D03*
X238614Y217763D03*
X222496Y222320D03*
X223129Y210901D03*
X224664Y293860D03*
X257400Y403206D03*
X239600Y405600D03*
X237800Y411200D03*
X226576Y401835D03*
X228243Y380358D03*
X231915Y380533D03*
X244928Y367685D03*
X238151Y356092D03*
X228510Y367624D03*
X240715Y380333D03*
X222269Y402278D03*
X228949Y410741D03*
X225421Y410908D03*
X269840Y386256D03*
X239693Y396029D03*
X257500Y399300D03*
X264600Y380500D03*
X270800Y408500D03*
X261300Y402355D03*
X275500Y415400D03*
X264124Y408219D03*
X258267Y408800D03*
X233400Y409700D03*
X255010Y367624D03*
X273554Y386722D03*
X223600Y456200D03*
X246502Y472752D03*
X255622Y461532D03*
X263000Y438800D03*
X260600Y435900D03*
X258299Y432800D03*
X250400Y440000D03*
X249600Y428100D03*
X237700Y458000D03*
X269300Y486200D03*
X249600Y432500D03*
X239000Y440300D03*
X244800Y454500D03*
X229600Y460700D03*
X289200Y445100D03*
X252200Y486700D03*
X290300Y462400D03*
X290011Y456234D03*
X289000Y449200D03*
X221035Y453935D03*
X279120Y440440D03*
X276761Y443421D03*
X277575Y449398D03*
X270714Y458323D03*
X263719Y455536D03*
X259779Y456823D03*
X220768Y418393D03*
X260322Y462288D03*
X256852Y465331D03*
X258221Y469246D03*
X235069Y464940D03*
X257184Y421241D03*
X271342Y440630D03*
X235600Y433300D03*
X264775Y459236D03*
X279789Y432846D03*
X285565Y438912D03*
X250400Y473300D03*
X260481Y473769D03*
X253214Y469048D03*
X228400Y486400D03*
X228001Y474064D03*
X226000Y458700D03*
X249845Y469508D03*
X229300Y442500D03*
X225700Y496800D03*
X226115Y507011D03*
X229513Y507141D03*
X232912Y507242D03*
X224515Y532633D03*
X237336Y531828D03*
X236700Y539300D03*
X240400Y534500D03*
X245800D03*
X241300Y539300D03*
X236300Y535600D03*
X243200Y531700D03*
X288586Y493703D03*
X268215Y490733D03*
X251755Y491731D03*
X270700Y495400D03*
X274315Y497133D03*
X283657Y532832D03*
X280259Y532714D03*
X232200Y492100D03*
X231739Y495469D03*
X248286Y489208D03*
X242100Y489000D03*
X268600Y529800D03*
X256300Y531400D03*
X289400Y511700D03*
X243300Y527900D03*
X247256Y529218D03*
X251700Y531500D03*
X268500Y525800D03*
X238118Y492166D03*
X246132Y492160D03*
X289405Y515437D03*
X228500Y498900D03*
X281183Y592936D03*
X223671Y740896D03*
X228249Y761450D03*
X223129Y764830D03*
X271970Y798668D03*
X282413Y798410D03*
X228021Y787335D03*
X223596Y782163D03*
X236973Y795418D03*
X237950Y774979D03*
X237815Y779065D03*
X226949Y782735D03*
X235169Y791455D03*
X240130Y789012D03*
X277254Y852624D03*
X314000Y405200D03*
X316800Y415900D03*
X299800Y398500D03*
X332600Y400100D03*
X305456Y481787D03*
X335532Y485626D03*
X323215Y485633D03*
X304783Y467192D03*
X295115Y476433D03*
Y473033D03*
X297715Y479588D03*
X306603Y459523D03*
X301437Y426833D03*
X304200Y432600D03*
X300603Y432406D03*
X309200Y444700D03*
X331800Y440400D03*
X331900Y444600D03*
X356700Y437500D03*
X348800D03*
X341500Y437400D03*
X291300Y468600D03*
X308900Y449100D03*
X327900Y438100D03*
X341430Y459351D03*
X345735Y460843D03*
X349800Y460000D03*
X353698Y460323D03*
X357812Y460406D03*
X297238Y429641D03*
X304550Y424222D03*
X300059Y422844D03*
X318015Y493833D03*
X334315Y496733D03*
X330815Y493433D03*
X327115Y489533D03*
X344815Y494933D03*
X321415Y497133D03*
X304000Y538500D03*
X308800Y540925D03*
X350400Y512000D03*
X335600Y511400D03*
X304700Y509500D03*
X317900Y520100D03*
X314628Y517729D03*
X343905Y519116D03*
X324400Y570500D03*
X346510Y796385D03*
X350765D03*
X315696Y798445D03*
X294148Y798547D03*
X305437Y798205D03*
X362793Y77815D03*
Y126096D03*
X381025Y73748D03*
Y120650D03*
X373496Y140021D03*
X365131Y135484D03*
X413900Y396400D03*
X428343Y463067D03*
X420575Y467336D03*
X382695Y467033D03*
Y471133D03*
X388884Y468631D03*
X387143Y462647D03*
X378700Y437600D03*
X371200Y437800D03*
X363800Y437700D03*
X428616Y429466D03*
X391500Y459000D03*
X399900Y458600D03*
X421273Y439381D03*
X361533Y460222D03*
X365241Y460010D03*
X416588Y467839D03*
X361814Y796557D03*
X500295Y401715D03*
X501800Y387600D03*
X473838Y385675D03*
X474106Y382285D03*
X500526Y394177D03*
X473605Y389068D03*
X499764Y411324D03*
X497279Y382551D03*
X435138Y460661D03*
X457091Y486699D03*
X475600Y462100D03*
X452300Y420900D03*
X458900Y446600D03*
X483100Y449900D03*
X488500Y474200D03*
X450300Y459900D03*
X471300Y482200D03*
X449000Y480000D03*
X438316Y449493D03*
X438294Y453811D03*
X501700Y477200D03*
X483530Y541762D03*
X487073Y554094D03*
X482183Y535169D03*
X483008Y500529D03*
X469932Y518034D03*
X447307Y511890D03*
X447090Y497242D03*
X471410Y490049D03*
X498994Y488322D03*
X501802Y490240D03*
X494400Y493600D03*
Y497500D03*
X471650Y493916D03*
X494410Y501344D03*
X458713Y518034D03*
X482200Y529100D03*
X484200Y538000D03*
X483800Y545700D03*
X452652Y495705D03*
X465900Y501200D03*
X523200Y399400D03*
X506100Y380000D03*
X517041Y388700D03*
X513500Y399060D03*
X520900Y388100D03*
X536928Y411324D03*
X514000Y486293D03*
X508306Y428179D03*
X523462Y423957D03*
X503923Y423910D03*
X536736Y418540D03*
X504500Y479500D03*
X514073Y552477D03*
X503300Y539700D03*
X529000Y550500D03*
X502318Y535328D03*
X521002Y555911D03*
X525300Y552800D03*
X516900Y561200D03*
X528000Y562900D03*
X512700Y560000D03*
X637200Y393900D03*
X629100Y536000D03*
X632600Y555200D03*
X636200Y555100D03*
X640100Y550600D03*
X638300Y511800D03*
X641800Y519000D03*
X639500Y521900D03*
X641700Y510300D03*
X662100Y394600D03*
X667979Y486293D03*
X702400Y431500D03*
X698300Y431600D03*
X702000Y485700D03*
X688615Y485133D03*
X693509Y431701D03*
X689111Y431612D03*
X684869Y431611D03*
X680738Y431633D03*
X711409Y467621D03*
X707700Y476500D03*
X707890Y467821D03*
X684259Y476130D03*
X682774Y449737D03*
X667745Y456089D03*
X662604Y463284D03*
X671915Y543133D03*
X694700Y547700D03*
X688800Y540450D03*
X702400Y554800D03*
X705927Y538650D03*
X663600Y535395D03*
X644600Y556700D03*
X652400Y545200D03*
X674375Y509826D03*
X700512Y510204D03*
X643833Y549325D03*
X702000Y546581D03*
X702400Y550600D03*
X684600Y542100D03*
X682015Y493633D03*
X665499Y556600D03*
X651800Y540295D03*
X711400Y515400D03*
X711900Y521500D03*
X675400Y538100D03*
X662200Y547300D03*
X709600Y524100D03*
X658314Y526697D03*
X672168Y538889D03*
X676115Y542633D03*
X712102Y542133D03*
X707589Y515400D03*
X700900Y539500D03*
X669200Y559600D03*
X656817Y567131D03*
X697600Y560000D03*
X701400Y560200D03*
X707391Y564566D03*
X643100Y589900D03*
X689945Y758289D03*
X700989Y759255D03*
X667982Y739870D03*
X681402Y757754D03*
X663575Y742289D03*
X668987Y731465D03*
X691075Y820814D03*
X711116Y796516D03*
X702290Y820921D03*
X680480Y773302D03*
X678755Y784815D03*
X676727Y790555D03*
X679630Y795856D03*
X680239Y802378D03*
X682693Y806283D03*
X684732Y810518D03*
X669886Y786112D03*
X666516Y784722D03*
X686308Y834802D03*
X646342Y826469D03*
X685799Y770894D03*
X690211Y827401D03*
X683715Y852233D03*
X710727Y862002D03*
X678351Y854383D03*
X679332Y841866D03*
X681156Y844982D03*
X681542Y848361D03*
X722687Y120650D03*
X727300Y273200D03*
X758200Y338900D03*
X756700Y370600D03*
X762900Y387400D03*
X768000Y457700D03*
X767700Y473300D03*
X729700Y551500D03*
X729600Y540400D03*
X724000Y532600D03*
X722682Y538700D03*
X716300Y517125D03*
X719800Y525000D03*
X719866Y528656D03*
X751965Y522097D03*
X747886D03*
X757848Y513543D03*
X752874Y534854D03*
X737297Y517903D03*
X756523Y520272D03*
X749493Y535216D03*
X725100Y519600D03*
X746000Y549700D03*
X726800Y527400D03*
X723538Y526440D03*
X742607Y549481D03*
X752100Y506500D03*
X749500Y508800D03*
X742000Y505000D03*
X762275Y512870D03*
X744073Y522097D03*
X755862Y516303D03*
X756400Y508100D03*
X756272Y534995D03*
X763000Y490800D03*
X717879Y564572D03*
X725900Y561800D03*
X737400Y576200D03*
X766358Y564600D03*
X727700Y584400D03*
X758400Y568500D03*
X742600Y577100D03*
X756100Y658700D03*
X757600Y639700D03*
X746669Y740179D03*
X743653Y744114D03*
X741453Y748054D03*
X738850Y751989D03*
X734450Y755929D03*
X730967Y759864D03*
X724305Y770450D03*
X723678Y774016D03*
X727477Y775212D03*
X724733Y779559D03*
X730028Y782297D03*
X724859Y784497D03*
X742663Y788885D03*
X729988Y787114D03*
X739510Y795264D03*
X725239Y788970D03*
X745230Y793211D03*
X729486Y791416D03*
X742370Y799077D03*
X725407Y794540D03*
X747659Y796960D03*
X744790Y802781D03*
X749593Y803991D03*
X747556Y808994D03*
X749629Y812608D03*
X722443Y826463D03*
X721704Y829981D03*
X724858Y831254D03*
X723801Y834857D03*
X726332Y837128D03*
X733066Y836450D03*
X729250Y850000D03*
X721243Y850725D03*
X718263Y863827D03*
X745100Y859405D03*
X721112Y854419D03*
X724093Y840187D03*
X726776Y842277D03*
X733796Y854172D03*
X932850Y589645D03*
G54D12*
X-59094Y277559D03*
X-7913D03*
X932850Y235045D03*
G54D21*
X109410Y796831D03*
Y876397D03*
X168465Y796831D03*
Y876397D03*
X932850Y412345D03*
G54D13*
X4800Y48600D03*
X5800Y6400D03*
X5000Y71900D03*
Y91900D03*
X5100Y111800D03*
X4900Y130400D03*
X5000Y150500D03*
X5300Y170000D03*
X9151Y473051D03*
X8672Y487593D03*
X7075Y527972D03*
X7927Y509647D03*
X8140Y637282D03*
X8246Y771416D03*
X45700Y61000D03*
X65500Y60800D03*
X75500D03*
X45900Y50000D03*
X65700Y49800D03*
X50800Y39500D03*
X70700Y45800D03*
X55800Y61300D03*
X59900Y40600D03*
X53200Y26300D03*
X50600Y6000D03*
X50500Y67700D03*
X70500Y72000D03*
X60800Y72500D03*
X57200Y175300D03*
X16158Y477255D03*
X39600Y494800D03*
X38200Y490900D03*
X35100Y494400D03*
X33600Y512600D03*
X37329Y524472D03*
X33880Y526500D03*
X33921Y520414D03*
X18809Y491871D03*
X17212Y532250D03*
X18064Y513925D03*
X18277Y641560D03*
X9844Y658803D03*
X19981Y663081D03*
X9631Y753837D03*
X19768Y758115D03*
X18383Y775694D03*
X55459Y780063D03*
X48300Y775300D03*
X87900Y47800D03*
X90900Y42400D03*
X80400Y47800D03*
X124100Y6700D03*
X110800Y48800D03*
X120200Y48400D03*
X98700Y48900D03*
X143900Y38000D03*
X108100Y35300D03*
X146900Y48500D03*
X109700Y6400D03*
X119700Y35400D03*
X139800Y31100D03*
X96300Y6100D03*
X147200Y7300D03*
X108600Y19900D03*
X126500Y20100D03*
X147500Y90200D03*
X142167Y106366D03*
X142101Y98650D03*
X111100Y75500D03*
X100000Y75600D03*
X121700Y75300D03*
X85300Y70200D03*
X126300Y180209D03*
X126700Y173500D03*
X136291Y179968D03*
X136100Y173800D03*
X134200Y217300D03*
X130000Y217200D03*
X134600Y222200D03*
X106051Y767209D03*
X122899Y825236D03*
X112762Y820958D03*
X116188Y771487D03*
X131900Y893200D03*
X120874Y857517D03*
X110737Y853239D03*
X131700Y915700D03*
X89871Y917500D03*
X209100Y51700D03*
X191700Y63300D03*
X209200Y65100D03*
X200700Y51700D03*
X185100Y55900D03*
X208900Y58600D03*
X192000Y55900D03*
X200700Y58300D03*
X184700Y63100D03*
X173200Y10900D03*
X213700Y35200D03*
X186000D03*
X197796Y12653D03*
X160600Y49100D03*
X153200Y48700D03*
X167500Y49000D03*
X160500Y19700D03*
X170400Y31100D03*
X150600Y37800D03*
X154500Y90000D03*
X158000Y79600D03*
X165200Y79500D03*
X163300Y95900D03*
X163500Y105500D03*
X151800Y72400D03*
X209000Y72300D03*
X201500D03*
X177100Y99500D03*
X177200Y104800D03*
X177300Y94200D03*
Y88500D03*
X184700D03*
X190700Y77800D03*
X201200Y65600D03*
X191000Y71300D03*
X184500Y71200D03*
X177400Y71400D03*
X177500Y77900D03*
X183700Y78100D03*
X191500Y88500D03*
X204200Y126700D03*
X206600Y130300D03*
X201900D03*
X207495Y192761D03*
X169800Y155796D03*
X165162Y155909D03*
X169709Y160049D03*
X165388Y160094D03*
X196400Y585300D03*
X179000Y624800D03*
X193600Y702400D03*
X179100Y714600D03*
X202300Y742000D03*
X189273Y902478D03*
X213138Y905780D03*
X218729Y857629D03*
X200460Y913771D03*
X282282Y47189D03*
X286930D03*
X233900Y32500D03*
X252187Y23895D03*
X286651Y14571D03*
X224431Y15210D03*
X248900Y8400D03*
X282444Y106834D03*
X225919Y88394D03*
X225937Y80731D03*
X221710Y80767D03*
X221722Y88431D03*
X230158Y88359D03*
X230123Y80805D03*
X225851Y73774D03*
X221740Y73844D03*
X229870Y73970D03*
X228169Y68374D03*
X224169Y68520D03*
X228728Y96613D03*
X224285Y96750D03*
X258741Y193852D03*
X256823Y221979D03*
X246169Y246270D03*
X230774Y270268D03*
X241694Y274956D03*
X228635Y385956D03*
X232788Y385893D03*
X229764Y513034D03*
X234416Y512963D03*
X238924Y512390D03*
X243100Y516300D03*
X245963Y511890D03*
X250975Y511729D03*
X255500Y514000D03*
X264000Y513400D03*
X277300Y572500D03*
X259600Y568400D03*
X271949Y648699D03*
X272588Y681087D03*
X244248Y682153D03*
X255542Y665532D03*
X241904Y652321D03*
X289634Y659352D03*
X284520Y743307D03*
X282176Y713475D03*
X230823Y823850D03*
X253623Y867319D03*
X254262Y899707D03*
X225922Y900773D03*
X237216Y884152D03*
X223578Y870941D03*
X285585Y897363D03*
X283241Y867531D03*
X264212Y903112D03*
X299300Y41300D03*
X321300Y43200D03*
X351800Y42200D03*
X360500Y42600D03*
X330000Y42800D03*
X329900Y37100D03*
X321300D03*
X360500Y36700D03*
X291373Y47394D03*
X299300Y46400D03*
X351800Y36300D03*
X299600Y62100D03*
X351900Y62000D03*
X360200Y62300D03*
X329500Y62600D03*
X321300Y63100D03*
X325006Y15636D03*
X299500Y68200D03*
X352000Y68000D03*
X360200Y68200D03*
X329600D03*
X321400Y68500D03*
X344663Y108965D03*
X312275Y98098D03*
X354197Y158187D03*
X301140Y161383D03*
X352066Y262596D03*
X307320Y223390D03*
X301781Y258122D03*
X322022Y279856D03*
X320207Y428442D03*
X320166Y432442D03*
X309648Y582024D03*
X319679Y655730D03*
X320318Y688118D03*
X291978Y689184D03*
X303272Y672563D03*
X347378Y688332D03*
X358672Y671711D03*
X345034Y658500D03*
X302115Y693462D03*
X360803Y704312D03*
X333102Y737766D03*
X344396Y721145D03*
X330758Y707934D03*
X312221Y709853D03*
X312860Y742241D03*
X295814Y726686D03*
X319171Y767846D03*
X313959Y724732D03*
X354623Y896937D03*
X352279Y867105D03*
X313286Y863909D03*
X313925Y896297D03*
X296879Y880742D03*
X332436Y858576D03*
X337648Y901690D03*
X382100Y61900D03*
X401343Y58465D03*
X394098Y20059D03*
X362775D03*
X412506Y33484D03*
X382200Y68500D03*
X410025Y87658D03*
X390208Y180135D03*
X366982Y198886D03*
X407769Y204757D03*
X384668Y247681D03*
X376144Y279856D03*
X380956Y408290D03*
X376513Y408085D03*
X371865D03*
X380392Y416962D03*
X375949Y416757D03*
X371301D03*
X366653Y416484D03*
X367217Y407812D03*
X366719Y424200D03*
X371367Y424473D03*
X376015D03*
X380458Y424678D03*
X414894Y453432D03*
X419296Y449111D03*
X423572Y453454D03*
X419092Y457572D03*
X419225Y453324D03*
X410200Y474200D03*
X410179Y469769D03*
X375079Y654878D03*
X375718Y687266D03*
X430267Y679595D03*
X413860Y696428D03*
X400222Y683217D03*
X388817Y692040D03*
X420252Y725194D03*
X420891Y757582D03*
X392551Y758648D03*
X403845Y742027D03*
X390207Y728816D03*
X361442Y736700D03*
X430906Y711983D03*
X402566Y713049D03*
X395450Y767846D03*
X378868Y723311D03*
X421530Y814262D03*
X419186Y784430D03*
X429202Y894806D03*
X426858Y864974D03*
X382324Y863483D03*
X382963Y895871D03*
X365917Y880316D03*
X413927Y901690D03*
X397345Y857155D03*
X432682Y23909D03*
X472315Y23056D03*
X496393Y55871D03*
X457399Y46069D03*
X496109Y93412D03*
X457989Y78967D03*
X493200Y145500D03*
X451789Y154565D03*
X473097Y208901D03*
X453252Y250240D03*
X438300Y481200D03*
X434515Y483333D03*
X434412Y479334D03*
X432014Y476132D03*
X455846Y546626D03*
X465212Y726260D03*
X465851Y758648D03*
X437511Y759714D03*
X448805Y743093D03*
X435167Y729882D03*
X474587Y765253D03*
X445197Y719047D03*
X449231Y780808D03*
X449870Y813196D03*
X432824Y797641D03*
X476931Y795085D03*
X488225Y778464D03*
X499945Y828325D03*
X486307Y815114D03*
X456903Y861352D03*
X457542Y893740D03*
X440496Y878185D03*
X488651Y844946D03*
X499208Y899795D03*
X463674Y852891D03*
X557547Y24335D03*
X526213Y34431D03*
X555558Y100229D03*
X531425Y77545D03*
X545330Y147959D03*
X521476Y205704D03*
X509632Y174434D03*
X526688Y248818D03*
X566000Y536700D03*
X508224Y580873D03*
X549379Y653173D03*
X504632Y761631D03*
X505271Y794019D03*
X516352Y811492D03*
X562377Y833013D03*
X532332Y836635D03*
X516991Y843880D03*
X563016Y865401D03*
X534676Y866467D03*
X545970Y849846D03*
X545118Y880530D03*
X528711Y897363D03*
X515073Y884152D03*
X562590Y881808D03*
X510579Y854786D03*
X545757Y912918D03*
X517417Y913984D03*
X564934Y911640D03*
X573457Y59531D03*
X621826Y20111D03*
X591122Y33010D03*
X607704Y77545D03*
X586385Y204283D03*
X596334Y173012D03*
X602967Y248818D03*
X633923Y520400D03*
X587942Y582024D03*
X614582Y653599D03*
X604141Y675547D03*
X578784Y682152D03*
X582620Y653386D03*
X632693Y697281D03*
X607550Y703460D03*
X628006Y720720D03*
X592635Y878186D03*
X576228Y895019D03*
X640791Y876268D03*
X641430Y908656D03*
X613090Y909722D03*
X624384Y893101D03*
X610746Y879890D03*
X593274Y910574D03*
X660180Y56547D03*
X657451Y28746D03*
X703700Y30300D03*
X651658Y95968D03*
X692985Y75650D03*
X699619Y201914D03*
X652714Y200019D03*
X692512Y162589D03*
X661673Y260892D03*
X688248Y246923D03*
X712386Y297542D03*
X711500Y438300D03*
X694995Y453626D03*
X694923Y461253D03*
X694851Y469456D03*
X694907Y476993D03*
X644900Y538300D03*
X668135Y523360D03*
X672161Y528021D03*
X676550Y523677D03*
X672342Y519560D03*
X672257Y523769D03*
X678293Y698772D03*
X675736Y657222D03*
X694061Y681726D03*
X654641Y691101D03*
X643987Y664041D03*
X697897Y662763D03*
X708231Y730948D03*
X681276Y722211D03*
X650805Y716671D03*
X698962Y707936D03*
X692356Y875629D03*
X692995Y908017D03*
X664655Y909083D03*
X675949Y892462D03*
X662311Y879251D03*
X754800Y56800D03*
Y36800D03*
Y16800D03*
X723466Y60810D03*
X721334Y17767D03*
X754800Y76800D03*
X754700Y117600D03*
Y97600D03*
X734333Y88085D03*
X754700Y197600D03*
Y177600D03*
Y157600D03*
Y137600D03*
Y257600D03*
Y237600D03*
Y217600D03*
Y277600D03*
X753800Y303200D03*
X767300Y340400D03*
X766900Y333754D03*
X735134Y289819D03*
X767000Y410900D03*
X766700Y403500D03*
X766900Y395400D03*
Y387800D03*
Y364600D03*
Y356300D03*
X767600Y348500D03*
X767400Y481600D03*
Y465900D03*
X767500Y450800D03*
X767300Y441747D03*
X766500Y435100D03*
X766800Y427000D03*
X767100Y418700D03*
Y544600D03*
X766800Y535700D03*
X767200Y524500D03*
X766900Y497700D03*
X767200Y489700D03*
X767100Y623900D03*
Y614800D03*
X766700Y606900D03*
X767700Y600200D03*
X766700Y592700D03*
X767000Y584300D03*
Y576100D03*
Y569500D03*
X726000Y650700D03*
X720000Y650800D03*
X733000Y650600D03*
X740000D03*
X766900Y639500D03*
Y631900D03*
X715795Y697494D03*
X750300Y663000D03*
X740513Y687906D03*
X745733Y713048D03*
X764200Y813000D03*
X745413Y854763D03*
X716221Y876694D03*
X729859Y889905D03*
X718565Y906526D03*
X746905Y905460D03*
X746266Y873072D03*
X932850Y560095D03*
G54D22*
X144843Y812994D03*
Y860234D03*
X932850Y353245D03*
G54D23*
X286982Y828335D03*
X276982D03*
X286982Y818335D03*
X276982D03*
X356982Y828335D03*
X346982D03*
X336982D03*
X326982D03*
X316982D03*
X306982D03*
X296982D03*
X356982Y818335D03*
X346982D03*
X336982D03*
X326982D03*
X316982D03*
X306982D03*
X296982D03*
X366982Y828335D03*
Y818335D03*
X932850Y441895D03*
G54D14*
X-33503Y269685D03*
X932850Y294145D03*
G54D24*
X716535Y39370D03*
X932850Y205495D03*
G54D15*
X8789Y376072D03*
X6944Y414616D03*
X6855Y436844D03*
X6750Y425868D03*
X7180Y449205D03*
X62439Y413744D03*
X66931Y398350D03*
X74863Y390483D03*
X64055Y389700D03*
X33722Y401639D03*
X74544Y414071D03*
X70779Y402387D03*
X79016Y410283D03*
X35738Y406956D03*
X14422Y411528D03*
X14657Y416838D03*
X10615Y411073D03*
X26551Y394546D03*
X30232Y416556D03*
X23922Y415548D03*
X35994Y410146D03*
X43719Y414419D03*
X32141Y407501D03*
X31808Y410684D03*
X18448Y402542D03*
X74817Y409752D03*
X26972Y399588D03*
X70882Y409794D03*
X66938Y410045D03*
X78939Y414083D03*
X18448Y406788D03*
X53976Y389814D03*
X74894Y398251D03*
X62031Y399713D03*
X70775Y398396D03*
X70845Y405839D03*
X70952Y414050D03*
X54515Y396433D03*
X54463Y386651D03*
X70865Y390502D03*
X74702Y394300D03*
X74869Y406315D03*
X78300Y386505D03*
X64948Y386626D03*
X78362Y398337D03*
X77963Y381183D03*
X70888Y394222D03*
X66963Y473083D03*
X66931Y484968D03*
X79081Y465348D03*
X70704Y429620D03*
X67015Y449433D03*
X74639Y441855D03*
X78754Y453353D03*
X78811Y426113D03*
X52151Y456887D03*
X66903Y457689D03*
X78798Y433983D03*
X17072Y435057D03*
X74836Y453477D03*
X59980Y482517D03*
X78754Y449904D03*
X67112Y481066D03*
X70488Y465291D03*
X74450Y457429D03*
X70713Y461504D03*
X36237Y441728D03*
X70908Y457771D03*
X70898Y418271D03*
X61038Y424878D03*
X74726Y425594D03*
X59209Y438908D03*
X46853Y441796D03*
X78561Y421756D03*
X70809Y438057D03*
X43659Y432766D03*
X43088Y438073D03*
X45486Y456341D03*
X38566Y451290D03*
X42312Y463368D03*
X74780Y429794D03*
X24357Y423051D03*
X37988Y438328D03*
X19757Y418538D03*
X29472Y428016D03*
X78738Y429679D03*
X11964Y421332D03*
X52476Y439395D03*
X13062Y429279D03*
X74656Y421838D03*
X17936Y431103D03*
X14206Y433632D03*
X15424Y422722D03*
X70857Y433857D03*
X19015Y426461D03*
X14147Y438989D03*
X74752Y437655D03*
X74437Y473159D03*
X15872Y441916D03*
X74460Y461287D03*
X78793Y445704D03*
X70868Y477094D03*
X23748Y436249D03*
X26611Y441743D03*
X70909Y469595D03*
X30513Y437850D03*
X74702Y469183D03*
X37420Y461517D03*
X31517Y445328D03*
X70868Y473157D03*
X28472Y447107D03*
X48298Y454813D03*
X70602Y453533D03*
X79050Y457367D03*
X74805Y481031D03*
X66991Y476766D03*
X62798Y461555D03*
X74451Y465323D03*
X79094Y441620D03*
X74801Y433368D03*
X70869Y421840D03*
X70759Y449277D03*
X74805Y477094D03*
X70868Y481031D03*
X74598Y485021D03*
X78421Y473078D03*
X74695Y449260D03*
X59063Y485583D03*
X79134Y461339D03*
X78742Y488905D03*
X66961Y488885D03*
X74805Y492842D03*
X74870Y488789D03*
X69523Y567387D03*
X69555Y564187D03*
X69569Y594959D03*
X69520Y560987D03*
X68421Y570392D03*
X69323Y579887D03*
X69518Y604727D03*
X69599Y601527D03*
X69569Y598159D03*
X69388Y576660D03*
X69450Y573460D03*
X69569Y608021D03*
X69496Y611417D03*
X69661Y591387D03*
X66579Y592250D03*
X63125Y592801D03*
X62681Y589462D03*
X69451Y684303D03*
Y681103D03*
X68928Y687846D03*
X69316Y697605D03*
X69451Y691003D03*
X69474Y694403D03*
X69523Y718313D03*
Y715113D03*
X69472Y729385D03*
X69548Y726185D03*
X69558Y711913D03*
X68620Y722610D03*
X106419Y310245D03*
X126184Y310860D03*
X93200Y308800D03*
X145771Y414191D03*
X82555Y406288D03*
X110472Y394496D03*
X145765Y406438D03*
X122053Y406224D03*
X114175Y410161D03*
X125990Y394413D03*
X141738D03*
X98427Y414098D03*
X125990D03*
X90553Y410161D03*
X102263Y414083D03*
X141887Y410202D03*
X102364Y406224D03*
X133864Y410161D03*
X94367Y394479D03*
X102364Y402287D03*
X106301Y398350D03*
Y402287D03*
X102364Y398350D03*
X110238Y402287D03*
X114175D03*
X110238Y398350D03*
X114175D03*
X85721Y385798D03*
X149362Y413951D03*
X149498Y406396D03*
X145795Y410173D03*
X149431Y394402D03*
X149783Y390487D03*
X110238Y410161D03*
X141738Y414098D03*
X133863Y413773D03*
X114175Y414098D03*
X122053D03*
X125990Y410161D03*
X94579Y406324D03*
X118130Y398511D03*
X98427Y410161D03*
X90553Y414098D03*
X86563Y402383D03*
X133964Y394555D03*
X102555Y394412D03*
X86616Y394413D03*
X86463Y390483D03*
X114175Y406224D03*
X126063Y406183D03*
X141738Y406224D03*
X106301D03*
X149663Y410083D03*
X82459Y413976D03*
X90566Y394383D03*
X82663Y402406D03*
X133864Y402287D03*
X86772Y414047D03*
X122053Y402287D03*
X133864Y398350D03*
X137801D03*
X122053D03*
X137801Y402287D03*
X125990D03*
Y398350D03*
X129927Y402287D03*
Y398350D03*
X82663Y398383D03*
X141738Y402287D03*
Y398350D03*
X145865Y402287D03*
Y398350D03*
X149488Y402114D03*
X149583Y398383D03*
X90359Y469275D03*
X137801Y453472D03*
Y445598D03*
X133864Y437720D03*
Y445598D03*
X133953Y425813D03*
X102684Y445671D03*
X106263Y437583D03*
X133864Y433783D03*
X102364Y429846D03*
X98363Y421883D03*
X94263Y418129D03*
X106210Y421976D03*
X110332Y425814D03*
X149612Y445598D03*
Y433783D03*
X86493Y441401D03*
X86616Y433783D03*
X86687Y421669D03*
X137801Y477094D03*
X149612D03*
X114175D03*
X102364D03*
X98626Y477049D03*
X130081Y425912D03*
X121943Y425834D03*
X114091Y425962D03*
X122053Y421972D03*
Y418035D03*
X106301D03*
X114175D03*
X133863Y417883D03*
X117951Y437592D03*
X114175Y445598D03*
X110263Y441683D03*
X118189Y445711D03*
X125990Y445598D03*
X110238Y437720D03*
X125990D03*
X110222Y417989D03*
X106341Y426062D03*
X82564Y449659D03*
X145663Y441483D03*
X98288Y441609D03*
X149612Y429846D03*
X110238Y453472D03*
X122053Y429846D03*
X114063Y429879D03*
X125897Y453240D03*
X118238Y453417D03*
X149594Y480923D03*
X94518Y449186D03*
X86768Y449383D03*
X98427Y484968D03*
Y481031D03*
X102364D03*
Y484968D03*
X106301D03*
Y481031D03*
X114175Y484968D03*
Y481031D03*
X122053Y484968D03*
Y481031D03*
X125990Y484968D03*
Y481031D03*
X145567Y453547D03*
X145763Y449583D03*
X149576Y465497D03*
X98597Y457291D03*
X94490Y429846D03*
X90463Y425983D03*
X90480Y437608D03*
X82562Y425980D03*
X86505Y425987D03*
X90380Y429650D03*
X130080Y457372D03*
X94490Y437720D03*
X82681Y430041D03*
X141827Y461346D03*
X98334Y429754D03*
X98427Y437720D03*
X94369Y425977D03*
X82677Y433595D03*
X149563Y469220D03*
X94490Y433783D03*
X141738Y481031D03*
X82663Y457486D03*
X141738Y484968D03*
X98433Y449125D03*
X137801Y481031D03*
X102600Y425983D03*
X137801Y484968D03*
X94554Y421911D03*
X133864Y481031D03*
X149612Y437720D03*
X94414Y445605D03*
X133864Y484968D03*
X86663Y429536D03*
X82542Y445403D03*
X98427Y433783D03*
X86568Y445669D03*
X90426Y449431D03*
X90563Y417983D03*
X145675Y425909D03*
X82573Y441360D03*
X145675Y437720D03*
X98280Y445405D03*
X90426Y441880D03*
X145675Y481031D03*
Y484968D03*
X145737Y418077D03*
X145675Y473157D03*
Y465283D03*
X149719Y457328D03*
X129927Y473157D03*
Y465283D03*
X137801Y461346D03*
Y457409D03*
X114175Y473157D03*
X122053Y469220D03*
X110263Y469083D03*
X122053Y473157D03*
X90350Y473069D03*
X82679Y477094D03*
X90662Y461604D03*
X106263Y453483D03*
X106449Y465157D03*
X122053Y445598D03*
X126180Y418224D03*
X137801Y437720D03*
X137767Y425993D03*
X129927Y445598D03*
X141738Y449535D03*
X133864Y421972D03*
Y429846D03*
X98533Y418180D03*
X118134Y449362D03*
X106363Y441583D03*
X110238Y445598D03*
X110289Y422113D03*
X122053Y437720D03*
X114175D03*
X94661Y441681D03*
X106263Y433683D03*
X90544Y433408D03*
X90408Y421930D03*
X129927Y437720D03*
X141738Y429846D03*
X86663Y453583D03*
X82732Y453139D03*
X102227Y473344D03*
X145675Y469220D03*
X90376Y476918D03*
X110238Y477094D03*
X141738D03*
X137801Y473157D03*
X98427Y469046D03*
X106301Y469220D03*
X114175D03*
X126057Y469287D03*
X129927Y469220D03*
X137801D03*
X122053Y465283D03*
X133864D03*
X106301Y461346D03*
X122113Y457535D03*
X129963Y461283D03*
X110263Y457283D03*
X122158Y453388D03*
X125990Y477094D03*
X137801Y449535D03*
X149612Y425909D03*
X82535Y461227D03*
X83021Y473118D03*
X141595Y421932D03*
X141775Y426153D03*
X86735Y461382D03*
X141763Y437883D03*
X86937Y477160D03*
X141682Y417902D03*
X82759Y469436D03*
X145663Y445583D03*
X145675Y429846D03*
X142008Y457429D03*
X141863Y445583D03*
X86959Y469276D03*
X137570Y421843D03*
X145561Y421879D03*
X90965Y465270D03*
X129927Y481031D03*
Y484968D03*
X110238Y481031D03*
Y484968D03*
X94490Y481031D03*
X86663Y457283D03*
X94490Y484968D03*
X86765Y465205D03*
X138061Y418151D03*
X145675Y433783D03*
X82763Y417750D03*
X86523Y417943D03*
X94844Y469182D03*
X102469Y469134D03*
X106149Y457371D03*
X141649Y453189D03*
X149620Y485149D03*
X98682Y461441D03*
X94092Y492819D03*
X141738Y488905D03*
X110238D03*
X125990D03*
X94377Y489070D03*
X118004Y488825D03*
X133864Y488905D03*
X149612D03*
X102308Y488978D03*
X86616Y488905D03*
X91852Y563129D03*
X91156Y572112D03*
X90823Y581387D03*
X91343Y598284D03*
X91023Y606587D03*
X90923Y616187D03*
X91198Y595087D03*
X91123Y591887D03*
X91223Y588487D03*
X159768Y238444D03*
X160004Y233894D03*
X181576Y407810D03*
X175463Y413760D03*
X161499Y402554D03*
X169297Y402536D03*
X157502Y390427D03*
X173425Y390228D03*
X214660Y362600D03*
X176751Y387090D03*
X157251Y414149D03*
X161477Y394511D03*
X180991Y398678D03*
X180809Y414170D03*
X179225Y403667D03*
X203410Y394323D03*
X182378Y390377D03*
X157574Y394185D03*
X161241Y398226D03*
X161277Y414114D03*
X174124Y402624D03*
X161213Y390551D03*
X169503Y386977D03*
X153587Y406496D03*
X157554Y402251D03*
X157698Y406313D03*
X161475Y410299D03*
X165266Y409882D03*
X165337Y414489D03*
X153528Y410052D03*
X165455Y398256D03*
X165229Y402019D03*
X157411Y398513D03*
X169113Y398299D03*
X178031Y390023D03*
X177588Y482616D03*
X161423Y469220D03*
X153583Y461058D03*
X169297Y477094D03*
Y465283D03*
X157486Y437720D03*
Y429846D03*
X153416Y445539D03*
X169290Y417960D03*
X169297Y437720D03*
X169112Y453260D03*
X169166Y429679D03*
X153549Y429846D03*
X165621Y418066D03*
X153549Y425909D03*
X161746Y421972D03*
X177182Y467018D03*
X175477Y472360D03*
X176815Y479061D03*
X161473Y457213D03*
X165360Y477094D03*
X153549Y437720D03*
X157560Y445484D03*
X153549Y449535D03*
X174859Y469220D03*
X157322Y453385D03*
X165317Y461561D03*
X165360Y473157D03*
X161455Y453385D03*
X177763Y486293D03*
X153463Y453383D03*
X157411Y469344D03*
X161423Y477094D03*
X157486Y461346D03*
X153690Y469111D03*
X165411Y429590D03*
X175161Y434723D03*
X161423Y445598D03*
X153549Y421972D03*
X161423Y484968D03*
Y481031D03*
X157486Y473157D03*
X165360Y469220D03*
X153549Y477094D03*
X173234Y465283D03*
Y453472D03*
X174086Y484839D03*
X175150Y476294D03*
X174351Y429014D03*
X161423Y437720D03*
X153549Y433783D03*
X161363Y425780D03*
X173234Y437720D03*
X173155Y417978D03*
X153422Y441722D03*
X161423Y449430D03*
X153549Y473157D03*
X161670Y418161D03*
X176662Y418122D03*
X153201Y418097D03*
X157401Y418143D03*
X157463Y421883D03*
X157486Y425909D03*
X173458Y457178D03*
X178053Y474260D03*
X174601Y481467D03*
X165319Y453134D03*
X165353Y480812D03*
X157486Y433783D03*
X165360Y421972D03*
X153646Y457393D03*
X161294Y461561D03*
X165363Y425783D03*
X157393Y457572D03*
X165217Y457361D03*
X165355Y433382D03*
X161423Y473157D03*
X165355Y437582D03*
X165360Y445598D03*
X157411Y449556D03*
X169157Y445598D03*
X157508Y480990D03*
X165288Y449306D03*
X157486Y484968D03*
X153601Y480894D03*
X153586Y485118D03*
X161423Y433783D03*
X181414Y490281D03*
X174475Y488016D03*
X178084Y493198D03*
X157486Y488905D03*
X165360D03*
X169297Y492842D03*
X161423D03*
X159589Y817543D03*
X157422Y825918D03*
X158725Y835536D03*
X159688Y832484D03*
X159431Y838974D03*
X159688Y829234D03*
X159137Y820712D03*
X160735Y857183D03*
X154730Y847010D03*
X159688Y851564D03*
X159560Y842172D03*
X159426Y848357D03*
X651000Y467700D03*
X646163Y482677D03*
X643296Y477617D03*
X643914Y470592D03*
X648652Y470028D03*
X654990Y463513D03*
X658399Y460842D03*
X659485Y455066D03*
X666818Y452921D03*
X710645Y447266D03*
X678767Y447136D03*
X672583Y467901D03*
X667831Y479556D03*
X662166Y456914D03*
X661760Y460089D03*
X646246Y475961D03*
X646794Y472634D03*
X682915Y467823D03*
X708059Y449951D03*
X671145Y454348D03*
X658195Y464248D03*
X653351Y470098D03*
X650837Y472421D03*
X646251Y479161D03*
X675745Y448189D03*
X685815Y496140D03*
X689996Y496274D03*
X694169Y496394D03*
X698475Y496387D03*
X702670Y496148D03*
X707296Y496348D03*
X716700Y445400D03*
X742200Y472500D03*
X724300Y454000D03*
X719100Y478900D03*
X744986Y481255D03*
X749974Y477780D03*
X749628Y471196D03*
X739751Y469686D03*
X735295Y463720D03*
X738636Y457903D03*
X731780Y452531D03*
X729478Y459116D03*
X721600Y451000D03*
X719700Y485600D03*
X735191Y453967D03*
X735231Y457167D03*
X746845Y476389D03*
Y473189D03*
X717993Y451389D03*
X731751Y464398D03*
X735259Y469898D03*
X721445Y455789D03*
X726589Y460909D03*
X743520Y478297D03*
X738745Y472789D03*
X713845Y447289D03*
X932850Y619195D03*
G54D25*
G01X-771361Y-182763D02*
Y-262763D01*
G01Y-218263D02*
X373639D01*
G01X-771361Y-262763D02*
X373639D01*
G01X-775361Y-166763D02*
G02I-12000J0D01*
G01X-780511D02*
G02I-6850J0D01*
G01X-787361Y-182763D02*
Y-150763D01*
G01X-771361Y-166763D02*
X-803361D01*
G01X-771361Y-182763D02*
X373639D01*
G01X-413861D02*
Y-262763D01*
G01X-276361Y-182763D02*
Y-262763D01*
G01X-161361Y-182763D02*
Y-262763D01*
G01X6139Y-182763D02*
Y-262763D01*
G01X176139Y-182763D02*
Y-262763D01*
G01X373639Y-182763D02*
Y-262763D01*
G01X401639Y-166763D02*
G02I-12000J0D01*
G01X396489D02*
G02I-6850J0D01*
G01X389639Y-182763D02*
Y-150763D01*
G01X405639Y-166763D02*
X373639D01*
G54D16*
X6614Y553544D03*
X10551Y623622D03*
X6614Y671654D03*
X10551Y741732D03*
X18425Y553544D03*
X32204D03*
X18425Y623622D03*
X32204D03*
X18425Y671654D03*
X32204D03*
X18425Y741732D03*
X32204D03*
X932850Y530545D03*
G54D26*
G01X-1003937Y-3937D02*
G03X-1000000Y-7874I3937J0D01*
G01X-1031496Y-31496D02*
G03X-1027559Y-35433I3937J0D01*
G01X-986221Y-7874D02*
G03Y0I0J3937D01*
G01Y-7874D02*
X-1000000D01*
G01X-1027559Y-35433D02*
X791338D01*
G01X-1031496Y95866D02*
Y-31496D01*
G01X-996063Y3937D02*
G03X-992126Y0I3937J0D01*
G01X-996063Y39370D02*
G03X-1003937I-3937J0D01*
G01X-996063Y3937D02*
G03X-992126Y0I3937J0D01*
G01D02*
X-318898D01*
G01D02*
X-992126D01*
G01X-955512D02*
X-986221D01*
G01X-996063Y3937D02*
Y103740D01*
G01Y39370D02*
Y70079D01*
G01X-1003937Y-3937D02*
Y39370D01*
G01X-1027559Y99803D02*
G03X-1031496Y95866I0J-3937D01*
G01X-1003937D02*
G03X-1007874Y99803I-3937J0D01*
G01X-996063Y103740D02*
G03X-1000000Y107677I-3937J0D01*
G01X-1003937Y70079D02*
G03X-996063I3937J0D01*
G01X-1029528Y107677D02*
X-1000000D01*
G01X-1007874Y99803D02*
X-1027559D01*
G01X-1003937Y70079D02*
Y95866D01*
G01X-1031496Y109646D02*
X-1029528Y107677D01*
G01X-1031496Y109646D02*
Y134055D01*
G01X-1002166Y136024D02*
G03Y143504I0J3740D01*
G01X-1000000Y187599D02*
G03X-996063Y191536I0J3937D01*
G01X-1029528Y187599D02*
X-1000000D01*
G01X-1029528Y143504D02*
X-1002166D01*
G01X-1029528Y136024D02*
X-1002166D01*
G01X-1029528D02*
X-1031496Y134055D01*
G01X-1029528Y187599D02*
X-1031496Y185630D01*
G01Y145473D02*
X-1029528Y143504D01*
G01X-996063Y261221D02*
Y191536D01*
G01X-1031496Y145473D02*
Y185630D01*
G01X-996063Y261221D02*
G03X-1000000Y265158I-3937J0D01*
G01X-1029528D02*
X-1000000D01*
G01X-1031496Y267126D02*
X-1029528Y265158D01*
G01X-1031496Y267126D02*
Y543504D01*
G01X-1002166Y545473D02*
G03Y552953I0J3740D01*
G01X-1029528D02*
X-1002166D01*
G01X-1029528Y545473D02*
X-1002166D01*
G01X-1031496Y554922D02*
X-1029528Y552953D01*
G01Y545473D02*
X-1031496Y543504D01*
G01Y554922D02*
Y595079D01*
G01X-1007874Y604922D02*
G03X-1003937Y608859I0J3937D01*
G01X-1031496D02*
G03X-1027559Y604922I3937J0D01*
G01X-1000000Y597048D02*
G03X-996063Y600985I0J3937D01*
G01X-1027559Y604922D02*
X-1007874D01*
G01X-1029528Y597048D02*
X-1000000D01*
G01X-1029528D02*
X-1031496Y595079D01*
G01X-996063Y921260D02*
Y600985D01*
G01X-1003937Y608859D02*
Y708662D01*
G01X-1031496Y956693D02*
Y608859D01*
G01X-1003937Y739370D02*
G03X-996063I3937J0D01*
G01Y708662D02*
G03X-1003937I-3937J0D01*
G01X-996063D02*
Y739370D01*
G01X-1003937D02*
Y929134D01*
G01X-992126Y925197D02*
G03X-996063Y921260I0J-3937D01*
G01X-1000000Y933071D02*
G03X-1003937Y929134I0J-3937D01*
G01X-986221Y925197D02*
G03Y933071I0J3937D01*
G01X-1027559Y960630D02*
G03X-1031496Y956693I0J-3937D01*
G01X-992126Y925197D02*
G03X-996063Y921260I0J-3937D01*
G01X791338Y960630D02*
X-1027559D01*
G01X-1000000Y933071D02*
X-986221D01*
G01X-992126Y925197D02*
X-240158D01*
G01X-986221D02*
X-955512D01*
G01X-992126D02*
X-240158D01*
G01X-955512Y0D02*
G03Y-7874I0J-3937D01*
G01X-769685D02*
X-955512D01*
G01Y933071D02*
G03Y925197I0J-3937D01*
G01Y933071D02*
X-750000D01*
G01X-769685Y-7874D02*
G03Y0I0J3937D01*
G01X-738977D02*
X-769685D01*
G01X-755164Y-252763D02*
Y-235263D01*
G01X-746868D02*
X-755164Y-246055D01*
G01X-745558Y-252763D02*
X-751453Y-241097D01*
G01X-737883Y-252763D02*
Y-235263D01*
X-727839Y-252763D01*
Y-235263D01*
G01X-715361Y-252763D02*
X-717108Y-252471D01*
X-718636Y-251305D01*
X-719946Y-249555D01*
X-720820Y-247513D01*
X-721256Y-245180D01*
Y-242846D01*
X-720820Y-240513D01*
X-719946Y-238471D01*
X-718636Y-236722D01*
X-717108Y-235555D01*
X-715361Y-235263D01*
X-713615Y-235555D01*
X-712086Y-236722D01*
X-710776Y-238471D01*
X-709902Y-240513D01*
X-709466Y-242846D01*
Y-245180D01*
X-709902Y-247513D01*
X-710776Y-249555D01*
X-712086Y-251305D01*
X-713615Y-252471D01*
X-715361Y-252763D01*
G01X-702446D02*
X-693276Y-235263D01*
G01X-702446D02*
X-693276Y-252763D01*
G01X-658494D02*
X-667228D01*
Y-235263D01*
X-658494D01*
G01X-661988Y-243721D02*
X-667228D01*
G01X-649946Y-252763D02*
X-640776Y-235263D01*
G01X-649946D02*
X-640776Y-252763D01*
G01X-632228D02*
Y-235263D01*
X-626988D01*
X-625241Y-236138D01*
X-623931Y-238180D01*
X-623494Y-240513D01*
X-623931Y-242846D01*
X-625023Y-244596D01*
X-626988Y-245472D01*
X-632228D01*
G01X-615820Y-252763D02*
X-610361Y-235263D01*
X-604902Y-252763D01*
G01X-606868Y-246638D02*
X-613855D01*
G01X-597883Y-252763D02*
Y-235263D01*
X-587839Y-252763D01*
Y-235263D01*
G01X-580164Y-252763D02*
Y-235263D01*
X-575798D01*
X-574051Y-236138D01*
X-572741Y-237305D01*
X-571649Y-239054D01*
X-570776Y-241097D01*
X-570558Y-244013D01*
X-570776Y-246930D01*
X-571649Y-248972D01*
X-572741Y-250722D01*
X-574051Y-251888D01*
X-575798Y-252763D01*
X-580164D01*
G01X-553494D02*
X-562228D01*
Y-235263D01*
X-553494D01*
G01X-556988Y-243721D02*
X-562228D01*
G01X-544728Y-252763D02*
Y-235263D01*
X-539269D01*
X-537523Y-236138D01*
X-536431Y-237305D01*
X-535994Y-239638D01*
X-536431Y-241972D01*
X-537741Y-243430D01*
X-539269Y-244305D01*
X-544728D01*
G01X-539269D02*
X-535994Y-252763D01*
G01X-503615Y-243430D02*
X-502741Y-242555D01*
X-502086Y-241097D01*
X-501649Y-239054D01*
X-502086Y-237305D01*
X-502959Y-236138D01*
X-504488Y-235263D01*
X-510383D01*
Y-252763D01*
X-503178D01*
X-501649Y-251597D01*
X-500776Y-249846D01*
X-500339Y-247805D01*
X-500776Y-245763D01*
X-502086Y-244013D01*
X-503615Y-243430D01*
X-510383D01*
G01X-487861Y-252763D02*
X-489608Y-252471D01*
X-491136Y-251305D01*
X-492446Y-249555D01*
X-493320Y-247513D01*
X-493756Y-245180D01*
Y-242846D01*
X-493320Y-240513D01*
X-492446Y-238471D01*
X-491136Y-236722D01*
X-489608Y-235555D01*
X-487861Y-235263D01*
X-486115Y-235555D01*
X-484586Y-236722D01*
X-483276Y-238471D01*
X-482402Y-240513D01*
X-481966Y-242846D01*
Y-245180D01*
X-482402Y-247513D01*
X-483276Y-249555D01*
X-484586Y-251305D01*
X-486115Y-252471D01*
X-487861Y-252763D01*
G01X-475820D02*
X-470361Y-235263D01*
X-464902Y-252763D01*
G01X-466868Y-246638D02*
X-473855D01*
G01X-457228Y-252763D02*
Y-235263D01*
X-451769D01*
X-450023Y-236138D01*
X-448931Y-237305D01*
X-448494Y-239638D01*
X-448931Y-241972D01*
X-450241Y-243430D01*
X-451769Y-244305D01*
X-457228D01*
G01X-451769D02*
X-448494Y-252763D01*
G01X-440164D02*
Y-235263D01*
X-435798D01*
X-434051Y-236138D01*
X-432741Y-237305D01*
X-431649Y-239054D01*
X-430776Y-241097D01*
X-430558Y-244013D01*
X-430776Y-246930D01*
X-431649Y-248972D01*
X-432741Y-250722D01*
X-434051Y-251888D01*
X-435798Y-252763D01*
X-440164D01*
G01X-738977Y0D02*
G03Y-7874I0J-3937D01*
G01X-522835D02*
X-738977D01*
G01X-719292Y933071D02*
G03Y925197I0J-3937D01*
G01X-750000D02*
G03Y933071I0J3937D01*
G01X-719292D02*
X-512992D01*
G01X-750000Y925197D02*
X-719292D01*
G01X-633538Y-207763D02*
Y-190263D01*
X-627861Y-204846D01*
X-622184Y-190263D01*
Y-207763D01*
G01X-610361D02*
X-611671Y-207471D01*
X-612981Y-206305D01*
X-613855Y-204263D01*
X-614291Y-201930D01*
X-613855Y-199596D01*
X-612981Y-197555D01*
X-611671Y-196388D01*
X-610361Y-196097D01*
X-609051Y-196388D01*
X-607741Y-197555D01*
X-606868Y-199596D01*
X-606649Y-201930D01*
X-606868Y-204263D01*
X-607741Y-206305D01*
X-609051Y-207471D01*
X-610361Y-207763D01*
G01X-588931Y-190263D02*
Y-207763D01*
G01Y-205139D02*
X-589804Y-206597D01*
X-591115Y-207471D01*
X-592643Y-207763D01*
X-594389Y-207180D01*
X-595699Y-205722D01*
X-596573Y-203972D01*
X-596791Y-201930D01*
X-596573Y-199888D01*
X-595699Y-198138D01*
X-594389Y-196680D01*
X-592643Y-196097D01*
X-591115Y-196388D01*
X-590023Y-196972D01*
X-588931Y-198138D01*
G01X-578636Y-199888D02*
X-571649D01*
X-572304Y-197846D01*
X-573396Y-196680D01*
X-574924Y-196097D01*
X-576453Y-196388D01*
X-577763Y-197263D01*
X-578636Y-199305D01*
X-579073Y-201055D01*
Y-202805D01*
X-578636Y-204555D01*
X-577544Y-206305D01*
X-576234Y-207471D01*
X-574706Y-207763D01*
X-573178Y-207180D01*
X-571649Y-205430D01*
G01X-557861Y-207763D02*
Y-190263D01*
G01X-522835Y-7874D02*
G03Y0I0J3937D01*
G01X-492126D02*
G03Y-7874I0J-3937D01*
G01X-365355D02*
X-492126D01*
G01Y0D02*
X-522835D01*
G01X-482284Y933071D02*
G03Y925197I0J-3937D01*
G01X-512992D02*
G03Y933071I0J3937D01*
G01Y925197D02*
X-482284D01*
G01Y933071D02*
X-316142D01*
G01X-380161Y-252763D02*
Y-235263D01*
X-382781Y-238763D01*
G01Y-252763D02*
X-377541D01*
G01X-366809Y-238180D02*
X-365499Y-236430D01*
X-363971Y-235555D01*
X-362224Y-235263D01*
X-360041Y-235846D01*
X-358513Y-237305D01*
X-358076Y-239054D01*
X-358294Y-240805D01*
X-359168Y-242263D01*
X-363534Y-245180D01*
X-365499Y-247221D01*
X-366809Y-250139D01*
X-367246Y-252763D01*
X-358076D01*
G01X-345161Y-235263D02*
X-346908Y-235846D01*
X-348218Y-237305D01*
X-349091Y-239054D01*
X-349746Y-241388D01*
X-349964Y-244013D01*
X-349746Y-246638D01*
X-349091Y-248972D01*
X-348218Y-250722D01*
X-346908Y-252180D01*
X-345161Y-252763D01*
X-343415Y-252180D01*
X-342104Y-250722D01*
X-341231Y-248972D01*
X-340576Y-246638D01*
X-340358Y-244013D01*
X-340576Y-241388D01*
X-341231Y-239054D01*
X-342104Y-237305D01*
X-343415Y-235846D01*
X-345161Y-235263D01*
G01X-327661D02*
X-329408Y-235846D01*
X-330718Y-237305D01*
X-331591Y-239054D01*
X-332246Y-241388D01*
X-332464Y-244013D01*
X-332246Y-246638D01*
X-331591Y-248972D01*
X-330718Y-250722D01*
X-329408Y-252180D01*
X-327661Y-252763D01*
X-325915Y-252180D01*
X-324604Y-250722D01*
X-323731Y-248972D01*
X-323076Y-246638D01*
X-322858Y-244013D01*
X-323076Y-241388D01*
X-323731Y-239054D01*
X-324604Y-237305D01*
X-325915Y-235846D01*
X-327661Y-235263D01*
G01X-307541Y-252763D02*
Y-235263D01*
X-315620Y-247805D01*
X-304702D01*
G01X-393278Y-207763D02*
Y-190263D01*
X-388038D01*
X-386291Y-191138D01*
X-384981Y-193180D01*
X-384544Y-195513D01*
X-384981Y-197846D01*
X-386073Y-199596D01*
X-388038Y-200472D01*
X-393278D01*
G01X-366608Y-191722D02*
X-367918Y-190846D01*
X-369446Y-190263D01*
X-371193D01*
X-373158Y-191138D01*
X-374686Y-192596D01*
X-375778Y-194347D01*
X-376651Y-197263D01*
X-376870Y-199888D01*
X-376433Y-202513D01*
X-375778Y-204263D01*
X-374468Y-206013D01*
X-372939Y-207180D01*
X-371411Y-207763D01*
X-369883D01*
X-368354Y-207180D01*
X-367044Y-206305D01*
X-365952Y-205139D01*
G01X-352165Y-198430D02*
X-351291Y-197555D01*
X-350636Y-196097D01*
X-350199Y-194054D01*
X-350636Y-192305D01*
X-351509Y-191138D01*
X-353038Y-190263D01*
X-358933D01*
Y-207763D01*
X-351728D01*
X-350199Y-206597D01*
X-349326Y-204846D01*
X-348889Y-202805D01*
X-349326Y-200763D01*
X-350636Y-199013D01*
X-352165Y-198430D01*
X-358933D01*
G01X-342961Y-213596D02*
X-329861D01*
G01X-323933Y-207763D02*
Y-190263D01*
X-313889Y-207763D01*
Y-190263D01*
G01X-301411Y-207763D02*
X-303158Y-207471D01*
X-304686Y-206305D01*
X-305996Y-204555D01*
X-306870Y-202513D01*
X-307306Y-200180D01*
Y-197846D01*
X-306870Y-195513D01*
X-305996Y-193471D01*
X-304686Y-191722D01*
X-303158Y-190555D01*
X-301411Y-190263D01*
X-299665Y-190555D01*
X-298136Y-191722D01*
X-296826Y-193471D01*
X-295952Y-195513D01*
X-295516Y-197846D01*
Y-200180D01*
X-295952Y-202513D01*
X-296826Y-204555D01*
X-298136Y-206305D01*
X-299665Y-207471D01*
X-301411Y-207763D01*
G01X-365355Y-7874D02*
G03Y0I0J3937D01*
G01X-334646D02*
X-365355D01*
G01X-311024Y-7874D02*
G03X-307087Y-3937I0J3937D01*
G01X-334646Y0D02*
G03Y-7874I0J-3937D01*
G01X-311024D02*
X-334646D01*
G01X-318898Y0D02*
G03X-314961Y3937I0J3937D01*
G01X-274410Y31595D02*
G03X-270473Y35532I0J3937D01*
G01X-303150Y31595D02*
G03X-307087Y27658I0J-3937D01*
G01X-318898Y0D02*
G03X-314961Y3937I0J3937D01*
G01X-307087Y27658D02*
Y-3937D01*
G01X-314961Y133859D02*
Y3937D01*
G01Y133859D02*
Y3937D01*
G01X-274410Y31595D02*
X-303150D01*
G01X-311024Y137796D02*
G03X-314961Y133859I0J-3937D01*
G01X-311024Y137796D02*
G03X-314961Y133859I0J-3937D01*
G01X-240158Y137796D02*
X-311024D01*
G01X-240158D02*
X-311024D01*
G01X-285433Y933071D02*
G03Y925197I0J-3937D01*
G01X-316142D02*
G03Y933071I0J3937D01*
G01X-285433D02*
X-224410D01*
G01X-316142Y925197D02*
X-285433D01*
G01X-218861Y-252763D02*
Y-235263D01*
X-221481Y-238763D01*
G01Y-252763D02*
X-216241D01*
G01X-250570Y-190263D02*
X-245111Y-207763D01*
X-239652Y-190263D01*
G01X-223244Y-207763D02*
X-231978D01*
Y-190263D01*
X-223244D01*
G01X-226738Y-198721D02*
X-231978D01*
G01X-214478Y-207763D02*
Y-190263D01*
X-209019D01*
X-207273Y-191138D01*
X-206181Y-192305D01*
X-205744Y-194638D01*
X-206181Y-196972D01*
X-207491Y-198430D01*
X-209019Y-199305D01*
X-214478D01*
G01X-209019D02*
X-205744Y-207763D01*
G01X-192611Y-208346D02*
X-193048Y-208055D01*
Y-207471D01*
X-192611Y-207180D01*
X-192174Y-207471D01*
Y-208055D01*
X-192611Y-208346D01*
G01X-270473Y125985D02*
Y35532D01*
G01X-266536Y129922D02*
G03X-270473Y125985I0J-3937D01*
G01X-260630Y129922D02*
G03Y137796I0J3937D01*
G01X-244882D02*
G03Y129922I0J-3937D01*
G01X-240158D02*
G03X-228347Y141733I0J11811D01*
G01X-260630Y129922D02*
X-266536D01*
G01X-240158D02*
X-244882D01*
G01X-240158Y137796D02*
G03X-236221Y141733I0J3937D01*
G01X-240158Y137796D02*
G03X-236221Y141733I0J3937D01*
G01X-228347Y368701D02*
Y141733D01*
G01X-236221Y413386D02*
Y141733D01*
G01X-244882Y137796D02*
X-260630D01*
G01X-204725Y409449D02*
G03X-208662Y405512I0J-3937D01*
G01X-232284Y417323D02*
G03X-236221Y413386I0J-3937D01*
G01X-232284Y417323D02*
G03X-236221Y413386I0J-3937D01*
G01X-212599Y372638D02*
G03X-208662Y376575I0J3937D01*
G01X-224410Y372638D02*
G03X-228347Y368701I0J-3937D01*
G01X-181103Y409449D02*
X-204725D01*
G01X-212599Y372638D02*
X-224410D01*
G01X-208662Y405512D02*
Y376575D01*
G01X-232284Y417323D02*
X-181103D01*
G01X-232284D02*
X-181103D01*
G01X-236221Y716536D02*
G03X-232284Y712599I3937J0D01*
G01X-224410Y724410D02*
G03X-220473Y720473I3937J0D01*
G01X-236221Y716536D02*
G03X-232284Y712599I3937J0D01*
G01X-220473Y720473D02*
X-96418D01*
G01Y712599D02*
X-232284D01*
G01X-96418D02*
X-232284D01*
G01X-224410Y933071D02*
Y724410D01*
G01X-236221Y921260D02*
Y716536D01*
G01Y921260D02*
G03X-240158Y925197I-3937J0D01*
G01X-236221Y921260D02*
G03X-240158Y925197I-3937J0D01*
G01X-143740Y216536D02*
G03X-139803Y212599I3937J0D01*
G01X-143740Y262205D02*
G03X-151614I-3937J0D01*
G01X-143740Y216536D02*
G03X-139803Y212599I3937J0D01*
G01X-151614Y216536D02*
G03X-139803Y204725I11811J0D01*
G01X-143740Y262205D02*
Y292914D01*
G01Y338583D02*
Y216536D01*
G01Y338583D02*
Y216536D01*
G01X-151614D02*
Y262205D01*
G01X-139803Y212599D02*
X-3937D01*
G01X-139803D02*
X-3937D01*
G01X-15748Y204725D02*
X-139803D01*
G01Y342520D02*
G03X-143740Y338583I0J-3937D01*
G01X-139803Y342520D02*
G03X-143740Y338583I0J-3937D01*
G01X-139803Y350394D02*
G03X-151614Y338583I0J-11811D01*
G01Y292914D02*
G03X-143740I3937J0D01*
G01X-151614D02*
Y338583D01*
G01X-62992Y342520D02*
X-139803D01*
G01X-62992D02*
X-139803D01*
G01X-181103Y409449D02*
G03X-169292Y421260I0J11811D01*
G01X-139803Y350394D02*
X-70866D01*
G01X-177166Y467717D02*
G03X-169292I3937J0D01*
G01X-181103Y417323D02*
G03X-177166Y421260I0J3937D01*
G01X-169292Y437008D02*
G03X-177166I-3937J0D01*
G01X-181103Y417323D02*
G03X-177166Y421260I0J3937D01*
G01X-169292Y437008D02*
Y421260D01*
G01Y570866D02*
Y467717D01*
G01X-177166Y421260D02*
Y578740D01*
G01Y421260D02*
Y578740D01*
G01Y467717D02*
Y437008D01*
G01X-173229Y582677D02*
G03X-177166Y578740I0J-3937D01*
G01X-165355Y574803D02*
G03X-169292Y570866I0J-3937D01*
G01X-173229Y582677D02*
G03X-177166Y578740I0J-3937D01*
G01X-173229Y582677D02*
X-96418D01*
G01X-173229D02*
X-96418D01*
G01Y574803D02*
X-165355D01*
G01X-117464Y-252763D02*
Y-235263D01*
X-113098D01*
X-111351Y-236138D01*
X-110041Y-237305D01*
X-108949Y-239054D01*
X-108076Y-241097D01*
X-107858Y-244013D01*
X-108076Y-246930D01*
X-108949Y-248972D01*
X-110041Y-250722D01*
X-111351Y-251888D01*
X-113098Y-252763D01*
X-117464D01*
G01X-99528D02*
Y-235263D01*
X-94069D01*
X-92323Y-236138D01*
X-91231Y-237305D01*
X-90794Y-239638D01*
X-91231Y-241972D01*
X-92541Y-243430D01*
X-94069Y-244305D01*
X-99528D01*
G01X-94069D02*
X-90794Y-252763D01*
G01X-80281Y-235263D02*
X-75041D01*
G01X-77661D02*
Y-252763D01*
G01X-80281D02*
X-75041D01*
G01X-64528Y-235263D02*
Y-252763D01*
X-55794D01*
G01X-47028Y-235263D02*
Y-252763D01*
X-38294D01*
G01X-125778Y-190263D02*
Y-207763D01*
X-117044D01*
G01X-99981D02*
Y-196097D01*
G01Y-198138D02*
X-100854Y-196972D01*
X-102165Y-196388D01*
X-103693Y-196097D01*
X-105221Y-196680D01*
X-106531Y-197846D01*
X-107405Y-199596D01*
X-107841Y-201930D01*
X-107405Y-204263D01*
X-106531Y-206013D01*
X-105221Y-207180D01*
X-103693Y-207763D01*
X-102165Y-207471D01*
X-100854Y-206597D01*
X-99981Y-205430D01*
G01X-90996Y-213013D02*
X-89686Y-213596D01*
X-87939Y-213013D01*
X-86848Y-211847D01*
X-85974Y-210388D01*
X-84665Y-205722D01*
X-81826Y-196097D01*
G01X-88813D02*
X-84665Y-205722D01*
G01X-72186Y-199888D02*
X-65199D01*
X-65854Y-197846D01*
X-66946Y-196680D01*
X-68474Y-196097D01*
X-70003Y-196388D01*
X-71313Y-197263D01*
X-72186Y-199305D01*
X-72623Y-201055D01*
Y-202805D01*
X-72186Y-204555D01*
X-71094Y-206305D01*
X-69784Y-207471D01*
X-68256Y-207763D01*
X-66728Y-207180D01*
X-65199Y-205430D01*
G01X-54468Y-207763D02*
Y-196097D01*
G01Y-198430D02*
X-53376Y-197263D01*
X-52284Y-196388D01*
X-50756Y-196097D01*
X-49665Y-196388D01*
X-48354Y-197263D01*
G01X-37186Y-205722D02*
X-36094Y-206888D01*
X-34566Y-207763D01*
X-33256D01*
X-31946Y-207180D01*
X-31073Y-206305D01*
X-30636Y-205139D01*
X-30854Y-203388D01*
X-31728Y-202513D01*
X-35658Y-200763D01*
X-36531Y-198721D01*
X-36094Y-197263D01*
X-35221Y-196388D01*
X-33911Y-196097D01*
X-32601Y-196388D01*
X-31291Y-197263D01*
G01X-62992Y342520D02*
G03X-59055Y346457I0J3937D01*
G01X-62992Y342520D02*
G03X-59055Y346457I0J3937D01*
G01X-70866Y350394D02*
G03X-66929Y354331I0J3937D01*
G01D02*
Y457481D01*
G01Y488189D02*
G03X-59055I3937J0D01*
G01Y457481D02*
G03X-66929I-3937J0D01*
G01X-55118Y515748D02*
G03X-66929Y503937I0J-11811D01*
G01Y488189D02*
Y503937D01*
G01X-96418Y582677D02*
G03X-92481Y586615I0J3937D01*
G01X-96418Y582677D02*
G03X-92481Y586615I0J3937D01*
G01X-96418Y574803D02*
G03X-84607Y586615I0J11811D01*
G01Y632284D02*
Y586615D01*
G01X-92481D02*
Y708662D01*
G01Y586615D02*
Y708662D01*
G01Y662992D02*
G03X-84607I3937J0D01*
G01Y632284D02*
G03X-92481I-3937J0D01*
G01X-84607Y708662D02*
Y662992D01*
G01X-92481D02*
Y632284D01*
G01Y708662D02*
G03X-96418Y712599I-3937J0D01*
G01X-92481Y708662D02*
G03X-96418Y712599I-3937J0D01*
G01X-84607Y708662D02*
G03X-96418Y720473I-11811J0D01*
G01X-11811Y-3937D02*
G03X-7874Y-7874I3937J0D01*
G01X31496D02*
X-7874D01*
G01X0Y3937D02*
G03X3937Y0I3937J0D01*
G01X0Y3937D02*
G03X3937Y0I3937J0D01*
G01X0Y3937D02*
Y208662D01*
G01X-11811Y-3937D02*
Y200788D01*
G01X755905Y0D02*
X3937D01*
G01X755905D02*
X3937D01*
G01X-11811Y200788D02*
G03X-15748Y204725I-3937J0D01*
G01X0Y208662D02*
G03X-3937Y212599I-3937J0D01*
G01X0Y208662D02*
G03X-3937Y212599I-3937J0D01*
G01X-59055Y503937D02*
Y346457D01*
G01Y503937D02*
Y346457D01*
G01Y488189D02*
Y457481D01*
G01X-23622Y552559D02*
G03X-27559Y548622I0J-3937D01*
G01X-11811Y552559D02*
G03X-7874Y556496I0J3937D01*
G01X-3937Y507874D02*
G03X0Y511811I0J3937D01*
G01X-3937Y507874D02*
G03X0Y511811I0J3937D01*
G01X-55118Y507874D02*
G03X-59055Y503937I0J-3937D01*
G01X-31496Y515748D02*
G03X-27559Y519685I0J3937D01*
G01X-55118Y507874D02*
G03X-59055Y503937I0J-3937D01*
G01X-23622Y552559D02*
X-11811D01*
G01X0Y511811D02*
Y783465D01*
G01X-27559Y519685D02*
Y548622D01*
G01X-55118Y515748D02*
X-31496D01*
G01X-3937Y507874D02*
X-55118D01*
G01X-3937D02*
X-55118D01*
G01X-7874Y556496D02*
Y783465D01*
G01X3937Y787402D02*
G03X0Y783465I0J-3937D01*
G01X3937Y787402D02*
G03X0Y783465I0J-3937D01*
G01X3937Y795276D02*
G03X-7874Y783465I0J-11811D01*
G01X3937Y795276D02*
X8661D01*
G01X3937Y787402D02*
X74803D01*
G01X3937D02*
X74803D01*
G01X51772Y-235263D02*
Y-252763D01*
X60506D01*
G01X68836Y-235263D02*
Y-247805D01*
X69709Y-250430D01*
X71456Y-252180D01*
X73639Y-252763D01*
X75822Y-252180D01*
X77569Y-250430D01*
X78442Y-247805D01*
Y-235263D01*
G01X95942Y-236722D02*
X94632Y-235846D01*
X93104Y-235263D01*
X91357D01*
X89392Y-236138D01*
X87864Y-237596D01*
X86772Y-239347D01*
X85899Y-242263D01*
X85680Y-244888D01*
X86117Y-247513D01*
X86772Y-249263D01*
X88082Y-251013D01*
X89611Y-252180D01*
X91139Y-252763D01*
X92667D01*
X94196Y-252180D01*
X95506Y-251305D01*
X96598Y-250139D01*
G01X103836Y-252763D02*
Y-235263D01*
G01X112132D02*
X103836Y-246055D01*
G01X113442Y-252763D02*
X107547Y-241097D01*
G01X126139Y-252763D02*
Y-244888D01*
X121772Y-235263D01*
G01X130506D02*
X126139Y-244888D01*
G01X25086Y-207763D02*
Y-190263D01*
X29452D01*
X31199Y-191138D01*
X32509Y-192305D01*
X33601Y-194054D01*
X34474Y-196097D01*
X34692Y-199013D01*
X34474Y-201930D01*
X33601Y-203972D01*
X32509Y-205722D01*
X31199Y-206888D01*
X29452Y-207763D01*
X25086D01*
G01X44114Y-199888D02*
X51101D01*
X50446Y-197846D01*
X49354Y-196680D01*
X47826Y-196097D01*
X46297Y-196388D01*
X44987Y-197263D01*
X44114Y-199305D01*
X43677Y-201055D01*
Y-202805D01*
X44114Y-204555D01*
X45206Y-206305D01*
X46516Y-207471D01*
X48044Y-207763D01*
X49572Y-207180D01*
X51101Y-205430D01*
G01X61614Y-205722D02*
X62706Y-206888D01*
X64234Y-207763D01*
X65544D01*
X66854Y-207180D01*
X67727Y-206305D01*
X68164Y-205139D01*
X67946Y-203388D01*
X67072Y-202513D01*
X63142Y-200763D01*
X62269Y-198721D01*
X62706Y-197263D01*
X63579Y-196388D01*
X64889Y-196097D01*
X66199Y-196388D01*
X67509Y-197263D01*
G01X82389Y-196097D02*
Y-207763D01*
G01Y-191430D02*
X81952Y-191138D01*
Y-190555D01*
X82389Y-190263D01*
X82826Y-190555D01*
Y-191138D01*
X82389Y-191430D01*
G01X96832Y-212138D02*
X98361Y-213305D01*
X100107Y-213596D01*
X101635Y-213305D01*
X102946Y-211847D01*
X103819Y-209805D01*
Y-196097D01*
G01Y-198430D02*
X102946Y-197263D01*
X101635Y-196388D01*
X100107Y-196097D01*
X98361Y-196680D01*
X97269Y-197846D01*
X96395Y-199888D01*
X95959Y-201930D01*
X96177Y-203680D01*
X97051Y-205722D01*
X98361Y-207180D01*
X100107Y-207763D01*
X101417Y-207471D01*
X102946Y-206305D01*
X103819Y-205139D01*
G01X113677Y-207763D02*
Y-196097D01*
G01Y-199013D02*
X114551Y-197555D01*
X115861Y-196388D01*
X117607Y-196097D01*
X119135Y-196388D01*
X120446Y-197555D01*
X121101Y-199596D01*
Y-207763D01*
G01X131614Y-199888D02*
X138601D01*
X137946Y-197846D01*
X136854Y-196680D01*
X135326Y-196097D01*
X133797Y-196388D01*
X132487Y-197263D01*
X131614Y-199305D01*
X131177Y-201055D01*
Y-202805D01*
X131614Y-204555D01*
X132706Y-206305D01*
X134016Y-207471D01*
X135544Y-207763D01*
X137072Y-207180D01*
X138601Y-205430D01*
G01X149332Y-207763D02*
Y-196097D01*
G01Y-198430D02*
X150424Y-197263D01*
X151516Y-196388D01*
X153044Y-196097D01*
X154135Y-196388D01*
X155446Y-197263D01*
G01X62204Y0D02*
G03Y-7874I0J-3937D01*
G01X31496D02*
G03Y0I0J3937D01*
G01X267716Y-7874D02*
X62204D01*
G01Y0D02*
X31496D01*
G01X74803Y787402D02*
G03X78740Y791339I0J3937D01*
G01X30315Y795276D02*
G03X34252Y799213I0J3937D01*
G01X24409Y795276D02*
G03Y787402I0J-3937D01*
G01X8661D02*
G03Y795276I0J3937D01*
G01X74803Y787402D02*
G03X78740Y791339I0J3937D01*
G01X24409Y795276D02*
X30315D01*
G01X24409Y787402D02*
X8661D01*
G01X34252Y799213D02*
Y889666D01*
G01X38189Y893603D02*
G03X34252Y889666I0J-3937D01*
G01X66929Y893603D02*
G03X70866Y897540I0J3937D01*
G01X38189Y893603D02*
X66929D01*
G01X70866Y897540D02*
Y929134D01*
G01X74803Y933071D02*
G03X70866Y929134I0J-3937D01*
G01X74803Y933071D02*
X88582D01*
G01X78740Y791339D02*
Y921260D01*
G01Y791339D02*
Y921260D01*
G01X119291Y933071D02*
G03Y925197I0J-3937D01*
G01X82677D02*
G03X78740Y921260I0J-3937D01*
G01X88582Y925197D02*
G03Y933071I0J3937D01*
G01X82677Y925197D02*
G03X78740Y921260I0J-3937D01*
G01X119291Y933071D02*
X305118D01*
G01X82677Y925197D02*
X755905D01*
G01X82677D02*
X755905D01*
G01X119291D02*
X88582D01*
G01X196089Y-252763D02*
Y-235263D01*
X193469Y-238763D01*
G01Y-252763D02*
X198709D01*
G01X213589Y-235263D02*
X211842Y-235846D01*
X210532Y-237305D01*
X209659Y-239054D01*
X209004Y-241388D01*
X208786Y-244013D01*
X209004Y-246638D01*
X209659Y-248972D01*
X210532Y-250722D01*
X211842Y-252180D01*
X213589Y-252763D01*
X215335Y-252180D01*
X216646Y-250722D01*
X217519Y-248972D01*
X218174Y-246638D01*
X218392Y-244013D01*
X218174Y-241388D01*
X217519Y-239054D01*
X216646Y-237305D01*
X215335Y-235846D01*
X213589Y-235263D01*
G01X227159Y-253346D02*
X235019Y-235263D01*
G01X248589Y-252763D02*
Y-235263D01*
X245969Y-238763D01*
G01Y-252763D02*
X251209D01*
G01X261941Y-245472D02*
X263469Y-243430D01*
X264779Y-242263D01*
X266526Y-241680D01*
X268054Y-242263D01*
X269146Y-243430D01*
X270019Y-245180D01*
X270237Y-247221D01*
X270019Y-248972D01*
X269146Y-250722D01*
X267835Y-252180D01*
X266307Y-252763D01*
X264561Y-252180D01*
X263032Y-250430D01*
X262159Y-247805D01*
X261941Y-244888D01*
X262377Y-241097D01*
X263032Y-239054D01*
X264124Y-237013D01*
X265652Y-235555D01*
X267181Y-235263D01*
X268709Y-235846D01*
X269801Y-237305D01*
G01X279659Y-253346D02*
X287519Y-235263D01*
G01X296941Y-238180D02*
X298251Y-236430D01*
X299779Y-235555D01*
X301526Y-235263D01*
X303709Y-235846D01*
X305237Y-237305D01*
X305674Y-239054D01*
X305456Y-240805D01*
X304582Y-242263D01*
X300216Y-245180D01*
X298251Y-247221D01*
X296941Y-250139D01*
X296504Y-252763D01*
X305674D01*
G01X318589Y-235263D02*
X316842Y-235846D01*
X315532Y-237305D01*
X314659Y-239054D01*
X314004Y-241388D01*
X313786Y-244013D01*
X314004Y-246638D01*
X314659Y-248972D01*
X315532Y-250722D01*
X316842Y-252180D01*
X318589Y-252763D01*
X320335Y-252180D01*
X321646Y-250722D01*
X322519Y-248972D01*
X323174Y-246638D01*
X323392Y-244013D01*
X323174Y-241388D01*
X322519Y-239054D01*
X321646Y-237305D01*
X320335Y-235846D01*
X318589Y-235263D01*
G01X336089Y-252763D02*
Y-235263D01*
X333469Y-238763D01*
G01Y-252763D02*
X338709D01*
G01X349441Y-238180D02*
X350751Y-236430D01*
X352279Y-235555D01*
X354026Y-235263D01*
X356209Y-235846D01*
X357737Y-237305D01*
X358174Y-239054D01*
X357956Y-240805D01*
X357082Y-242263D01*
X352716Y-245180D01*
X350751Y-247221D01*
X349441Y-250139D01*
X349004Y-252763D01*
X358174D01*
G01X243786Y-207763D02*
Y-190263D01*
X248152D01*
X249899Y-191138D01*
X251209Y-192305D01*
X252301Y-194054D01*
X253174Y-196097D01*
X253392Y-199013D01*
X253174Y-201930D01*
X252301Y-203972D01*
X251209Y-205722D01*
X249899Y-206888D01*
X248152Y-207763D01*
X243786D01*
G01X270019D02*
Y-196097D01*
G01Y-198138D02*
X269146Y-196972D01*
X267835Y-196388D01*
X266307Y-196097D01*
X264779Y-196680D01*
X263469Y-197846D01*
X262595Y-199596D01*
X262159Y-201930D01*
X262595Y-204263D01*
X263469Y-206013D01*
X264779Y-207180D01*
X266307Y-207763D01*
X267835Y-207471D01*
X269146Y-206597D01*
X270019Y-205430D01*
G01X283589Y-190263D02*
Y-207763D01*
G01X280532Y-196097D02*
X286646D01*
G01X297814Y-199888D02*
X304801D01*
X304146Y-197846D01*
X303054Y-196680D01*
X301526Y-196097D01*
X299997Y-196388D01*
X298687Y-197263D01*
X297814Y-199305D01*
X297377Y-201055D01*
Y-202805D01*
X297814Y-204555D01*
X298906Y-206305D01*
X300216Y-207471D01*
X301744Y-207763D01*
X303272Y-207180D01*
X304801Y-205430D01*
G01X267716Y-7874D02*
G03Y0I0J3937D01*
G01X298425D02*
X267716D01*
G01X298425D02*
G03Y-7874I0J-3937D01*
G01X483071D02*
X298425D01*
G01X335827Y933071D02*
G03Y925197I0J-3937D01*
G01X305118D02*
G03Y933071I0J3937D01*
G01X335827D02*
X522441D01*
G01X335827Y925197D02*
X305118D01*
G01X483071Y-7874D02*
G03Y0I0J3937D01*
G01X513779D02*
X483071D01*
G01X513779D02*
G03Y-7874I0J-3937D01*
G01X719291D02*
X513779D01*
G01X553149Y933071D02*
G03Y925197I0J-3937D01*
G01X522441D02*
G03Y933071I0J3937D01*
G01X553149D02*
X719291D01*
G01X553149Y925197D02*
X522441D01*
G01X763779Y-7874D02*
G03X767716Y-3937I0J3937D01*
G01X719291Y-7874D02*
G03Y0I0J3937D01*
G01X750000D02*
G03Y-7874I0J-3937D01*
G01X763779D02*
X750000D01*
G01X755905Y0D02*
G03X759842Y3937I0J3937D01*
G01X755905Y0D02*
G03X759842Y3937I0J3937D01*
G01X767716Y185827D02*
Y-3937D01*
G01X759842Y3937D02*
Y324213D01*
G01X750000Y0D02*
X719291D01*
G01X767716Y185827D02*
G03X759842I-3937J0D01*
G01Y216536D02*
Y185827D01*
G01Y216536D02*
G03X767716I3937J0D01*
G01Y316339D02*
Y216536D01*
G01X771653Y320276D02*
G03X767716Y316339I0J-3937D01*
G01X763779Y328150D02*
G03X759842Y324213I0J-3937D01*
G01X793307Y328150D02*
X763779D01*
G01X791338Y320276D02*
X771653D01*
G01X765945Y379725D02*
G03Y372244I0J-3741D01*
G01X793307Y379725D02*
X765945D01*
G01X793307Y372244D02*
X765945D01*
G01X759842Y663977D02*
G03X763779Y660040I3937J0D01*
G01X759842Y663977D02*
Y733662D01*
G01X793307Y660040D02*
X763779D01*
G01Y737599D02*
G03X759842Y733662I0J-3937D01*
G01X793307Y737599D02*
X763779D01*
G01X765945Y789174D02*
G03Y781693I0J-3740D01*
G01X767716Y829331D02*
G03X771653Y825394I3937J0D01*
G01X759842Y821457D02*
G03X763779Y817520I3937J0D01*
G01X767716Y855118D02*
Y829331D01*
G01X759842Y921260D02*
Y821457D01*
G01X771653Y825394D02*
X791338D01*
G01X793307Y817520D02*
X763779D01*
G01X793307Y789174D02*
X765945D01*
G01X793307Y781693D02*
X765945D01*
G01X767716Y855118D02*
G03X759842I-3937J0D01*
G01Y885827D02*
G03X767716I3937J0D01*
G01Y929134D02*
Y885827D01*
G01X759842D02*
Y855118D01*
G01Y921260D02*
G03X755905Y925197I-3937J0D01*
G01X767716Y929134D02*
G03X763779Y933071I-3937J0D01*
G01X750000D02*
G03Y925197I0J-3937D01*
G01X719291D02*
G03Y933071I0J3937D01*
G01X759842Y921260D02*
G03X755905Y925197I-3937J0D01*
G01X750000Y933071D02*
X763779D01*
G01X750000Y925197D02*
X719291D01*
G01X791338Y-35433D02*
G03X795275Y-31496I0J3937D01*
G01D02*
Y316339D01*
G01D02*
G03X791338Y320276I-3937J0D01*
G01X795275Y370276D02*
Y330118D01*
G01D02*
X793307Y328150D01*
G01X795275Y658071D02*
Y381693D01*
G01D02*
X793307Y379725D01*
G01X795275Y370276D02*
X793307Y372244D01*
G01X795275Y658071D02*
X793307Y660040D01*
G01X795275Y779725D02*
Y739567D01*
G01D02*
X793307Y737599D01*
G01X791338Y825394D02*
G03X795275Y829331I0J3937D01*
G01D02*
Y956693D01*
G01Y815552D02*
Y791142D01*
G01Y815552D02*
X793307Y817520D01*
G01X795275Y779725D02*
X793307Y781693D01*
G01X795275Y791142D02*
X793307Y789174D01*
G01X795275Y956693D02*
G03X791338Y960630I-3937J0D01*
G01X887900Y190720D02*
Y715170D01*
X1371500D01*
Y190720D01*
X887900D01*
G01Y249820D02*
X1371500D01*
G01X887900Y220270D02*
X1371500D01*
G01X887900Y338470D02*
X1371500D01*
G01X887900Y308920D02*
X1371500D01*
G01X887900Y279370D02*
X1371500D01*
G01X887900Y397570D02*
X1371500D01*
G01X887900Y368020D02*
X1371500D01*
G01X887900Y456670D02*
X1371500D01*
G01X887900Y427120D02*
X1371500D01*
G01X887900Y545320D02*
X1371500D01*
G01X887900Y515770D02*
X1371500D01*
G01X887900Y486220D02*
X1371500D01*
G01X887900Y604420D02*
X1371500D01*
G01X887900Y574870D02*
X1371500D01*
G01X898905Y643320D02*
Y655820D01*
X904795D01*
G01X902625Y649778D02*
X898905D01*
G01X912390Y655820D02*
X916110D01*
G01X914250D02*
Y643320D01*
G01X912390D02*
X916110D01*
G01X927580Y649570D02*
X930680D01*
Y645820D01*
X929750Y644570D01*
X928665Y643737D01*
X927115Y643320D01*
X925565Y643737D01*
X924480Y644570D01*
X923550Y645820D01*
X922930Y647278D01*
X922620Y648945D01*
Y650403D01*
X922930Y651653D01*
X923550Y653112D01*
X924480Y654362D01*
X925410Y655195D01*
X926650Y655820D01*
X927735D01*
X928975Y655403D01*
X929905Y654570D01*
G01X935640Y655820D02*
Y646862D01*
X936260Y644986D01*
X937500Y643737D01*
X939050Y643320D01*
X940600Y643737D01*
X941840Y644986D01*
X942460Y646862D01*
Y655820D01*
G01X948350Y643320D02*
Y655820D01*
X952225D01*
X953465Y655195D01*
X954240Y654362D01*
X954550Y652695D01*
X954240Y651028D01*
X953310Y649987D01*
X952225Y649362D01*
X948350D01*
G01X952225D02*
X954550Y643320D01*
G01X966950D02*
X960750D01*
Y655820D01*
X966950D01*
G01X964470Y649778D02*
X960750D01*
G01X887900Y690170D02*
X1371500D01*
G01X887900Y662070D02*
X1371500D01*
G01X887900Y633970D02*
X1371500D01*
G01X977800Y662070D02*
Y190720D01*
G01X971290Y696420D02*
Y708920D01*
X974390D01*
X975630Y708295D01*
X976560Y707462D01*
X977335Y706212D01*
X977955Y704753D01*
X978110Y702670D01*
X977955Y700587D01*
X977335Y699128D01*
X976560Y697878D01*
X975630Y697045D01*
X974390Y696420D01*
X971290D01*
G01X984000D02*
Y708920D01*
X987875D01*
X989115Y708295D01*
X989890Y707462D01*
X990200Y705795D01*
X989890Y704128D01*
X988960Y703087D01*
X987875Y702462D01*
X984000D01*
G01X987875D02*
X990200Y696420D01*
G01X997640Y708920D02*
X1001360D01*
G01X999500D02*
Y696420D01*
G01X997640D02*
X1001360D01*
G01X1008800Y708920D02*
Y696420D01*
X1015000D01*
G01X1021200Y708920D02*
Y696420D01*
X1027400D01*
G01X1052510Y707878D02*
X1051580Y708503D01*
X1050495Y708920D01*
X1049255D01*
X1047860Y708295D01*
X1046775Y707253D01*
X1046000Y706003D01*
X1045380Y703920D01*
X1045225Y702045D01*
X1045535Y700170D01*
X1046000Y698920D01*
X1046930Y697670D01*
X1048015Y696837D01*
X1049100Y696420D01*
X1050185D01*
X1051270Y696837D01*
X1052200Y697461D01*
X1052975Y698295D01*
G01X1058245Y696420D02*
Y708920D01*
G01X1064755D02*
Y696420D01*
G01Y702670D02*
X1058245D01*
G01X1070025Y696420D02*
X1073900Y708920D01*
X1077775Y696420D01*
G01X1076380Y700795D02*
X1071420D01*
G01X1083200Y696420D02*
Y708920D01*
X1087075D01*
X1088315Y708295D01*
X1089090Y707462D01*
X1089400Y705795D01*
X1089090Y704128D01*
X1088160Y703087D01*
X1087075Y702462D01*
X1083200D01*
G01X1087075D02*
X1089400Y696420D01*
G01X1098700Y708920D02*
Y696420D01*
G01X1095135Y708920D02*
X1102265D01*
G01X1111100Y696003D02*
X1110790Y696212D01*
Y696628D01*
X1111100Y696837D01*
X1111410Y696628D01*
Y696212D01*
X1111100Y696003D01*
G01Y701628D02*
X1110790Y701837D01*
Y702253D01*
X1111100Y702462D01*
X1111410Y702253D01*
Y701837D01*
X1111100Y701628D01*
G01X1135900Y708920D02*
Y696420D01*
G01X1132335Y708920D02*
X1139465D01*
G01X1148300Y696420D02*
X1147060Y696628D01*
X1145975Y697461D01*
X1145045Y698712D01*
X1144425Y700170D01*
X1144115Y701837D01*
Y703503D01*
X1144425Y705170D01*
X1145045Y706628D01*
X1145975Y707878D01*
X1147060Y708712D01*
X1148300Y708920D01*
X1149540Y708712D01*
X1150625Y707878D01*
X1151555Y706628D01*
X1152175Y705170D01*
X1152485Y703503D01*
Y701837D01*
X1152175Y700170D01*
X1151555Y698712D01*
X1150625Y697461D01*
X1149540Y696628D01*
X1148300Y696420D01*
G01X1157600D02*
Y708920D01*
X1161320D01*
X1162560Y708295D01*
X1163490Y706837D01*
X1163800Y705170D01*
X1163490Y703503D01*
X1162715Y702253D01*
X1161320Y701628D01*
X1157600D01*
G01X1185500Y708920D02*
Y696420D01*
G01X1183330Y704753D02*
X1187670D01*
G01X1197900Y696420D02*
X1196970Y696628D01*
X1196040Y697461D01*
X1195420Y698920D01*
X1195110Y700587D01*
X1195420Y702253D01*
X1196040Y703712D01*
X1196970Y704545D01*
X1197900Y704753D01*
X1198830Y704545D01*
X1199760Y703712D01*
X1200380Y702253D01*
X1200535Y700587D01*
X1200380Y698920D01*
X1199760Y697461D01*
X1198830Y696628D01*
X1197900Y696420D01*
G01X1223940Y703087D02*
X1224560Y703712D01*
X1225025Y704753D01*
X1225335Y706212D01*
X1225025Y707462D01*
X1224405Y708295D01*
X1223320Y708920D01*
X1219135D01*
Y696420D01*
X1224250D01*
X1225335Y697253D01*
X1225955Y698503D01*
X1226265Y699962D01*
X1225955Y701420D01*
X1225025Y702670D01*
X1223940Y703087D01*
X1219135D01*
G01X1235100Y696420D02*
X1233860Y696628D01*
X1232775Y697461D01*
X1231845Y698712D01*
X1231225Y700170D01*
X1230915Y701837D01*
Y703503D01*
X1231225Y705170D01*
X1231845Y706628D01*
X1232775Y707878D01*
X1233860Y708712D01*
X1235100Y708920D01*
X1236340Y708712D01*
X1237425Y707878D01*
X1238355Y706628D01*
X1238975Y705170D01*
X1239285Y703503D01*
Y701837D01*
X1238975Y700170D01*
X1238355Y698712D01*
X1237425Y697461D01*
X1236340Y696628D01*
X1235100Y696420D01*
G01X1247500Y708920D02*
Y696420D01*
G01X1243935Y708920D02*
X1251065D01*
G01X1259900D02*
Y696420D01*
G01X1256335Y708920D02*
X1263465D01*
G01X1272300Y696420D02*
X1271060Y696628D01*
X1269975Y697461D01*
X1269045Y698712D01*
X1268425Y700170D01*
X1268115Y701837D01*
Y703503D01*
X1268425Y705170D01*
X1269045Y706628D01*
X1269975Y707878D01*
X1271060Y708712D01*
X1272300Y708920D01*
X1273540Y708712D01*
X1274625Y707878D01*
X1275555Y706628D01*
X1276175Y705170D01*
X1276485Y703503D01*
Y701837D01*
X1276175Y700170D01*
X1275555Y698712D01*
X1274625Y697461D01*
X1273540Y696628D01*
X1272300Y696420D01*
G01X1280670D02*
Y708920D01*
X1284700Y698503D01*
X1288730Y708920D01*
Y696420D01*
G01X1047550Y199245D02*
Y211745D01*
X1045690Y209245D01*
G01Y199245D02*
X1049410D01*
G01X1057315Y200703D02*
X1058400Y199662D01*
X1059640Y199245D01*
X1060880Y199662D01*
X1061965Y200911D01*
X1062740Y202787D01*
X1063050Y204662D01*
Y206953D01*
X1062740Y208828D01*
X1061965Y210495D01*
X1061035Y211328D01*
X1059950Y211745D01*
X1058710Y211328D01*
X1057780Y210495D01*
X1057160Y209245D01*
X1056850Y207578D01*
X1057160Y206120D01*
X1057935Y204662D01*
X1058865Y203828D01*
X1059950Y203620D01*
X1061190Y204036D01*
X1062120Y205078D01*
X1063050Y206953D01*
G01X1072040Y199245D02*
X1072350Y201953D01*
X1072815Y204245D01*
X1073435Y206328D01*
X1074210Y208620D01*
X1075450Y211745D01*
X1069250D01*
G01X1084750Y198828D02*
X1084440Y199037D01*
Y199453D01*
X1084750Y199662D01*
X1085060Y199453D01*
Y199037D01*
X1084750Y198828D01*
G01X1097150Y211745D02*
X1095910Y211328D01*
X1094980Y210287D01*
X1094360Y209037D01*
X1093895Y207370D01*
X1093740Y205495D01*
X1093895Y203620D01*
X1094360Y201953D01*
X1094980Y200703D01*
X1095910Y199662D01*
X1097150Y199245D01*
X1098390Y199662D01*
X1099320Y200703D01*
X1099940Y201953D01*
X1100405Y203620D01*
X1100560Y205495D01*
X1100405Y207370D01*
X1099940Y209037D01*
X1099320Y210287D01*
X1098390Y211328D01*
X1097150Y211745D01*
G01X1047550Y258345D02*
Y270845D01*
X1045690Y268345D01*
G01Y258345D02*
X1049410D01*
G01X1061810D02*
Y270845D01*
X1056075Y261887D01*
X1063825D01*
G01X1072350Y270845D02*
X1071110Y270428D01*
X1070180Y269387D01*
X1069560Y268137D01*
X1069095Y266470D01*
X1068940Y264595D01*
X1069095Y262720D01*
X1069560Y261053D01*
X1070180Y259803D01*
X1071110Y258762D01*
X1072350Y258345D01*
X1073590Y258762D01*
X1074520Y259803D01*
X1075140Y261053D01*
X1075605Y262720D01*
X1075760Y264595D01*
X1075605Y266470D01*
X1075140Y268137D01*
X1074520Y269387D01*
X1073590Y270428D01*
X1072350Y270845D01*
G01X1084750Y257928D02*
X1084440Y258137D01*
Y258553D01*
X1084750Y258762D01*
X1085060Y258553D01*
Y258137D01*
X1084750Y257928D01*
G01X1097150Y270845D02*
X1095910Y270428D01*
X1094980Y269387D01*
X1094360Y268137D01*
X1093895Y266470D01*
X1093740Y264595D01*
X1093895Y262720D01*
X1094360Y261053D01*
X1094980Y259803D01*
X1095910Y258762D01*
X1097150Y258345D01*
X1098390Y258762D01*
X1099320Y259803D01*
X1099940Y261053D01*
X1100405Y262720D01*
X1100560Y264595D01*
X1100405Y266470D01*
X1099940Y268137D01*
X1099320Y269387D01*
X1098390Y270428D01*
X1097150Y270845D01*
G01X1047550Y228795D02*
Y241295D01*
X1045690Y238795D01*
G01Y228795D02*
X1049410D01*
G01X1056540Y230670D02*
X1057470Y229628D01*
X1058555Y229003D01*
X1059950Y228795D01*
X1061345Y229212D01*
X1062430Y230045D01*
X1063205Y231503D01*
X1063360Y233170D01*
X1063050Y234837D01*
X1062275Y235878D01*
X1061190Y236712D01*
X1060105Y236920D01*
X1059020Y236712D01*
X1057625Y235878D01*
X1058090Y241295D01*
X1062275D01*
G01X1072350Y228795D02*
X1073435Y229003D01*
X1074675Y229628D01*
X1075450Y230670D01*
X1075760Y232128D01*
X1075450Y233586D01*
X1074520Y234837D01*
X1073125Y235462D01*
X1071575D01*
X1070645Y235878D01*
X1069870Y236920D01*
X1069560Y238378D01*
X1070025Y239837D01*
X1071110Y240878D01*
X1072350Y241295D01*
X1073590Y240878D01*
X1074675Y239837D01*
X1075140Y238378D01*
X1074830Y236920D01*
X1074055Y235878D01*
X1073125Y235462D01*
X1071575D01*
X1070180Y234837D01*
X1069250Y233586D01*
X1068940Y232128D01*
X1069250Y230670D01*
X1070025Y229628D01*
X1071265Y229003D01*
X1072350Y228795D01*
G01X1084750Y228378D02*
X1084440Y228587D01*
Y229003D01*
X1084750Y229212D01*
X1085060Y229003D01*
Y228587D01*
X1084750Y228378D01*
G01X1097150Y241295D02*
X1095910Y240878D01*
X1094980Y239837D01*
X1094360Y238587D01*
X1093895Y236920D01*
X1093740Y235045D01*
X1093895Y233170D01*
X1094360Y231503D01*
X1094980Y230253D01*
X1095910Y229212D01*
X1097150Y228795D01*
X1098390Y229212D01*
X1099320Y230253D01*
X1099940Y231503D01*
X1100405Y233170D01*
X1100560Y235045D01*
X1100405Y236920D01*
X1099940Y238587D01*
X1099320Y239837D01*
X1098390Y240878D01*
X1097150Y241295D01*
G01X1050805Y352203D02*
X1051890Y353662D01*
X1052820Y354495D01*
X1054060Y354912D01*
X1055145Y354495D01*
X1055920Y353662D01*
X1056540Y352412D01*
X1056695Y350953D01*
X1056540Y349703D01*
X1055920Y348453D01*
X1054990Y347412D01*
X1053905Y346995D01*
X1052665Y347412D01*
X1051580Y348661D01*
X1050960Y350537D01*
X1050805Y352620D01*
X1051115Y355328D01*
X1051580Y356787D01*
X1052355Y358245D01*
X1053440Y359287D01*
X1054525Y359495D01*
X1055610Y359078D01*
X1056385Y358037D01*
G01X1066150Y346995D02*
Y359495D01*
X1064290Y356995D01*
G01Y346995D02*
X1068010D01*
G01X1078550Y346578D02*
X1078240Y346787D01*
Y347203D01*
X1078550Y347412D01*
X1078860Y347203D01*
Y346787D01*
X1078550Y346578D01*
G01X1090950Y359495D02*
X1089710Y359078D01*
X1088780Y358037D01*
X1088160Y356787D01*
X1087695Y355120D01*
X1087540Y353245D01*
X1087695Y351370D01*
X1088160Y349703D01*
X1088780Y348453D01*
X1089710Y347412D01*
X1090950Y346995D01*
X1092190Y347412D01*
X1093120Y348453D01*
X1093740Y349703D01*
X1094205Y351370D01*
X1094360Y353245D01*
X1094205Y355120D01*
X1093740Y356787D01*
X1093120Y358037D01*
X1092190Y359078D01*
X1090950Y359495D01*
G01X1050805Y322653D02*
X1051890Y324112D01*
X1052820Y324945D01*
X1054060Y325362D01*
X1055145Y324945D01*
X1055920Y324112D01*
X1056540Y322862D01*
X1056695Y321403D01*
X1056540Y320153D01*
X1055920Y318903D01*
X1054990Y317862D01*
X1053905Y317445D01*
X1052665Y317862D01*
X1051580Y319111D01*
X1050960Y320987D01*
X1050805Y323070D01*
X1051115Y325778D01*
X1051580Y327237D01*
X1052355Y328695D01*
X1053440Y329737D01*
X1054525Y329945D01*
X1055610Y329528D01*
X1056385Y328487D01*
G01X1063205Y327862D02*
X1064135Y329111D01*
X1065220Y329737D01*
X1066460Y329945D01*
X1068010Y329528D01*
X1069095Y328487D01*
X1069405Y327237D01*
X1069250Y325986D01*
X1068630Y324945D01*
X1065530Y322862D01*
X1064135Y321403D01*
X1063205Y319320D01*
X1062895Y317445D01*
X1069405D01*
G01X1078550Y317028D02*
X1078240Y317237D01*
Y317653D01*
X1078550Y317862D01*
X1078860Y317653D01*
Y317237D01*
X1078550Y317028D01*
G01X1090950Y329945D02*
X1089710Y329528D01*
X1088780Y328487D01*
X1088160Y327237D01*
X1087695Y325570D01*
X1087540Y323695D01*
X1087695Y321820D01*
X1088160Y320153D01*
X1088780Y318903D01*
X1089710Y317862D01*
X1090950Y317445D01*
X1092190Y317862D01*
X1093120Y318903D01*
X1093740Y320153D01*
X1094205Y321820D01*
X1094360Y323695D01*
X1094205Y325570D01*
X1093740Y327237D01*
X1093120Y328487D01*
X1092190Y329528D01*
X1090950Y329945D01*
G01X1053440Y287895D02*
X1053750Y290603D01*
X1054215Y292895D01*
X1054835Y294978D01*
X1055610Y297270D01*
X1056850Y300395D01*
X1050650D01*
G01X1063515Y289353D02*
X1064600Y288312D01*
X1065840Y287895D01*
X1067080Y288312D01*
X1068165Y289561D01*
X1068940Y291437D01*
X1069250Y293312D01*
Y295603D01*
X1068940Y297478D01*
X1068165Y299145D01*
X1067235Y299978D01*
X1066150Y300395D01*
X1064910Y299978D01*
X1063980Y299145D01*
X1063360Y297895D01*
X1063050Y296228D01*
X1063360Y294770D01*
X1064135Y293312D01*
X1065065Y292478D01*
X1066150Y292270D01*
X1067390Y292686D01*
X1068320Y293728D01*
X1069250Y295603D01*
G01X1078550Y287478D02*
X1078240Y287687D01*
Y288103D01*
X1078550Y288312D01*
X1078860Y288103D01*
Y287687D01*
X1078550Y287478D01*
G01X1090950Y300395D02*
X1089710Y299978D01*
X1088780Y298937D01*
X1088160Y297687D01*
X1087695Y296020D01*
X1087540Y294145D01*
X1087695Y292270D01*
X1088160Y290603D01*
X1088780Y289353D01*
X1089710Y288312D01*
X1090950Y287895D01*
X1092190Y288312D01*
X1093120Y289353D01*
X1093740Y290603D01*
X1094205Y292270D01*
X1094360Y294145D01*
X1094205Y296020D01*
X1093740Y297687D01*
X1093120Y298937D01*
X1092190Y299978D01*
X1090950Y300395D01*
G01X1051115Y407553D02*
X1052200Y406512D01*
X1053440Y406095D01*
X1054680Y406512D01*
X1055765Y407761D01*
X1056540Y409637D01*
X1056850Y411512D01*
Y413803D01*
X1056540Y415678D01*
X1055765Y417345D01*
X1054835Y418178D01*
X1053750Y418595D01*
X1052510Y418178D01*
X1051580Y417345D01*
X1050960Y416095D01*
X1050650Y414428D01*
X1050960Y412970D01*
X1051735Y411512D01*
X1052665Y410678D01*
X1053750Y410470D01*
X1054990Y410886D01*
X1055920Y411928D01*
X1056850Y413803D01*
G01X1063515Y407553D02*
X1064600Y406512D01*
X1065840Y406095D01*
X1067080Y406512D01*
X1068165Y407761D01*
X1068940Y409637D01*
X1069250Y411512D01*
Y413803D01*
X1068940Y415678D01*
X1068165Y417345D01*
X1067235Y418178D01*
X1066150Y418595D01*
X1064910Y418178D01*
X1063980Y417345D01*
X1063360Y416095D01*
X1063050Y414428D01*
X1063360Y412970D01*
X1064135Y411512D01*
X1065065Y410678D01*
X1066150Y410470D01*
X1067390Y410886D01*
X1068320Y411928D01*
X1069250Y413803D01*
G01X1078550Y405678D02*
X1078240Y405887D01*
Y406303D01*
X1078550Y406512D01*
X1078860Y406303D01*
Y405887D01*
X1078550Y405678D01*
G01X1090950Y418595D02*
X1089710Y418178D01*
X1088780Y417137D01*
X1088160Y415887D01*
X1087695Y414220D01*
X1087540Y412345D01*
X1087695Y410470D01*
X1088160Y408803D01*
X1088780Y407553D01*
X1089710Y406512D01*
X1090950Y406095D01*
X1092190Y406512D01*
X1093120Y407553D01*
X1093740Y408803D01*
X1094205Y410470D01*
X1094360Y412345D01*
X1094205Y414220D01*
X1093740Y415887D01*
X1093120Y417137D01*
X1092190Y418178D01*
X1090950Y418595D01*
G01X1047550Y376545D02*
Y389045D01*
X1045690Y386545D01*
G01Y376545D02*
X1049410D01*
G01X1057315Y378003D02*
X1058400Y376962D01*
X1059640Y376545D01*
X1060880Y376962D01*
X1061965Y378211D01*
X1062740Y380087D01*
X1063050Y381962D01*
Y384253D01*
X1062740Y386128D01*
X1061965Y387795D01*
X1061035Y388628D01*
X1059950Y389045D01*
X1058710Y388628D01*
X1057780Y387795D01*
X1057160Y386545D01*
X1056850Y384878D01*
X1057160Y383420D01*
X1057935Y381962D01*
X1058865Y381128D01*
X1059950Y380920D01*
X1061190Y381336D01*
X1062120Y382378D01*
X1063050Y384253D01*
G01X1072040Y376545D02*
X1072350Y379253D01*
X1072815Y381545D01*
X1073435Y383628D01*
X1074210Y385920D01*
X1075450Y389045D01*
X1069250D01*
G01X1084750Y376128D02*
X1084440Y376337D01*
Y376753D01*
X1084750Y376962D01*
X1085060Y376753D01*
Y376337D01*
X1084750Y376128D01*
G01X1097150Y389045D02*
X1095910Y388628D01*
X1094980Y387587D01*
X1094360Y386337D01*
X1093895Y384670D01*
X1093740Y382795D01*
X1093895Y380920D01*
X1094360Y379253D01*
X1094980Y378003D01*
X1095910Y376962D01*
X1097150Y376545D01*
X1098390Y376962D01*
X1099320Y378003D01*
X1099940Y379253D01*
X1100405Y380920D01*
X1100560Y382795D01*
X1100405Y384670D01*
X1099940Y386337D01*
X1099320Y387587D01*
X1098390Y388628D01*
X1097150Y389045D01*
G01X1050340Y467695D02*
X1051270Y466236D01*
X1052510Y465403D01*
X1053905Y465195D01*
X1055145Y465403D01*
X1056385Y466445D01*
X1057160Y467695D01*
X1057315Y468945D01*
X1057005Y470403D01*
X1055920Y471445D01*
X1054835Y471862D01*
X1053440D01*
G01X1054835D02*
X1055765Y472487D01*
X1056540Y473528D01*
X1056850Y474778D01*
X1056540Y476028D01*
X1055765Y477070D01*
X1054370Y477695D01*
X1052975Y477487D01*
X1051580Y476653D01*
G01X1063515Y466653D02*
X1064600Y465612D01*
X1065840Y465195D01*
X1067080Y465612D01*
X1068165Y466861D01*
X1068940Y468737D01*
X1069250Y470612D01*
Y472903D01*
X1068940Y474778D01*
X1068165Y476445D01*
X1067235Y477278D01*
X1066150Y477695D01*
X1064910Y477278D01*
X1063980Y476445D01*
X1063360Y475195D01*
X1063050Y473528D01*
X1063360Y472070D01*
X1064135Y470612D01*
X1065065Y469778D01*
X1066150Y469570D01*
X1067390Y469986D01*
X1068320Y471028D01*
X1069250Y472903D01*
G01X1078550Y464778D02*
X1078240Y464987D01*
Y465403D01*
X1078550Y465612D01*
X1078860Y465403D01*
Y464987D01*
X1078550Y464778D01*
G01X1090950Y477695D02*
X1089710Y477278D01*
X1088780Y476237D01*
X1088160Y474987D01*
X1087695Y473320D01*
X1087540Y471445D01*
X1087695Y469570D01*
X1088160Y467903D01*
X1088780Y466653D01*
X1089710Y465612D01*
X1090950Y465195D01*
X1092190Y465612D01*
X1093120Y466653D01*
X1093740Y467903D01*
X1094205Y469570D01*
X1094360Y471445D01*
X1094205Y473320D01*
X1093740Y474987D01*
X1093120Y476237D01*
X1092190Y477278D01*
X1090950Y477695D01*
G01X1055610Y435645D02*
Y448145D01*
X1049875Y439187D01*
X1057625D01*
G01X1062740Y437520D02*
X1063670Y436478D01*
X1064755Y435853D01*
X1066150Y435645D01*
X1067545Y436062D01*
X1068630Y436895D01*
X1069405Y438353D01*
X1069560Y440020D01*
X1069250Y441687D01*
X1068475Y442728D01*
X1067390Y443562D01*
X1066305Y443770D01*
X1065220Y443562D01*
X1063825Y442728D01*
X1064290Y448145D01*
X1068475D01*
G01X1078550Y435228D02*
X1078240Y435437D01*
Y435853D01*
X1078550Y436062D01*
X1078860Y435853D01*
Y435437D01*
X1078550Y435228D01*
G01X1090950Y448145D02*
X1089710Y447728D01*
X1088780Y446687D01*
X1088160Y445437D01*
X1087695Y443770D01*
X1087540Y441895D01*
X1087695Y440020D01*
X1088160Y438353D01*
X1088780Y437103D01*
X1089710Y436062D01*
X1090950Y435645D01*
X1092190Y436062D01*
X1093120Y437103D01*
X1093740Y438353D01*
X1094205Y440020D01*
X1094360Y441895D01*
X1094205Y443770D01*
X1093740Y445437D01*
X1093120Y446687D01*
X1092190Y447728D01*
X1090950Y448145D01*
G01X1053750Y553845D02*
Y566345D01*
X1051890Y563845D01*
G01Y553845D02*
X1055610D01*
G01X1063205Y559053D02*
X1064290Y560512D01*
X1065220Y561345D01*
X1066460Y561762D01*
X1067545Y561345D01*
X1068320Y560512D01*
X1068940Y559262D01*
X1069095Y557803D01*
X1068940Y556553D01*
X1068320Y555303D01*
X1067390Y554262D01*
X1066305Y553845D01*
X1065065Y554262D01*
X1063980Y555511D01*
X1063360Y557387D01*
X1063205Y559470D01*
X1063515Y562178D01*
X1063980Y563637D01*
X1064755Y565095D01*
X1065840Y566137D01*
X1066925Y566345D01*
X1068010Y565928D01*
X1068785Y564887D01*
G01X1078550Y553428D02*
X1078240Y553637D01*
Y554053D01*
X1078550Y554262D01*
X1078860Y554053D01*
Y553637D01*
X1078550Y553428D01*
G01X1090950Y566345D02*
X1089710Y565928D01*
X1088780Y564887D01*
X1088160Y563637D01*
X1087695Y561970D01*
X1087540Y560095D01*
X1087695Y558220D01*
X1088160Y556553D01*
X1088780Y555303D01*
X1089710Y554262D01*
X1090950Y553845D01*
X1092190Y554262D01*
X1093120Y555303D01*
X1093740Y556553D01*
X1094205Y558220D01*
X1094360Y560095D01*
X1094205Y561970D01*
X1093740Y563637D01*
X1093120Y564887D01*
X1092190Y565928D01*
X1090950Y566345D01*
G01X1050340Y526795D02*
X1051270Y525336D01*
X1052510Y524503D01*
X1053905Y524295D01*
X1055145Y524503D01*
X1056385Y525545D01*
X1057160Y526795D01*
X1057315Y528045D01*
X1057005Y529503D01*
X1055920Y530545D01*
X1054835Y530962D01*
X1053440D01*
G01X1054835D02*
X1055765Y531587D01*
X1056540Y532628D01*
X1056850Y533878D01*
X1056540Y535128D01*
X1055765Y536170D01*
X1054370Y536795D01*
X1052975Y536587D01*
X1051580Y535753D01*
G01X1063205Y534712D02*
X1064135Y535961D01*
X1065220Y536587D01*
X1066460Y536795D01*
X1068010Y536378D01*
X1069095Y535337D01*
X1069405Y534087D01*
X1069250Y532836D01*
X1068630Y531795D01*
X1065530Y529712D01*
X1064135Y528253D01*
X1063205Y526170D01*
X1062895Y524295D01*
X1069405D01*
G01X1078550Y523878D02*
X1078240Y524087D01*
Y524503D01*
X1078550Y524712D01*
X1078860Y524503D01*
Y524087D01*
X1078550Y523878D01*
G01X1090950Y536795D02*
X1089710Y536378D01*
X1088780Y535337D01*
X1088160Y534087D01*
X1087695Y532420D01*
X1087540Y530545D01*
X1087695Y528670D01*
X1088160Y527003D01*
X1088780Y525753D01*
X1089710Y524712D01*
X1090950Y524295D01*
X1092190Y524712D01*
X1093120Y525753D01*
X1093740Y527003D01*
X1094205Y528670D01*
X1094360Y530545D01*
X1094205Y532420D01*
X1093740Y534087D01*
X1093120Y535337D01*
X1092190Y536378D01*
X1090950Y536795D01*
G01X1050340Y497245D02*
X1051270Y495786D01*
X1052510Y494953D01*
X1053905Y494745D01*
X1055145Y494953D01*
X1056385Y495995D01*
X1057160Y497245D01*
X1057315Y498495D01*
X1057005Y499953D01*
X1055920Y500995D01*
X1054835Y501412D01*
X1053440D01*
G01X1054835D02*
X1055765Y502037D01*
X1056540Y503078D01*
X1056850Y504328D01*
X1056540Y505578D01*
X1055765Y506620D01*
X1054370Y507245D01*
X1052975Y507037D01*
X1051580Y506203D01*
G01X1062740Y496620D02*
X1063670Y495578D01*
X1064755Y494953D01*
X1066150Y494745D01*
X1067545Y495162D01*
X1068630Y495995D01*
X1069405Y497453D01*
X1069560Y499120D01*
X1069250Y500787D01*
X1068475Y501828D01*
X1067390Y502662D01*
X1066305Y502870D01*
X1065220Y502662D01*
X1063825Y501828D01*
X1064290Y507245D01*
X1068475D01*
G01X1078550Y494328D02*
X1078240Y494537D01*
Y494953D01*
X1078550Y495162D01*
X1078860Y494953D01*
Y494537D01*
X1078550Y494328D01*
G01X1090950Y507245D02*
X1089710Y506828D01*
X1088780Y505787D01*
X1088160Y504537D01*
X1087695Y502870D01*
X1087540Y500995D01*
X1087695Y499120D01*
X1088160Y497453D01*
X1088780Y496203D01*
X1089710Y495162D01*
X1090950Y494745D01*
X1092190Y495162D01*
X1093120Y496203D01*
X1093740Y497453D01*
X1094205Y499120D01*
X1094360Y500995D01*
X1094205Y502870D01*
X1093740Y504537D01*
X1093120Y505787D01*
X1092190Y506828D01*
X1090950Y507245D01*
G01X1053750Y612945D02*
Y625445D01*
X1051890Y622945D01*
G01Y612945D02*
X1055610D01*
G01X1066150Y625445D02*
X1064910Y625028D01*
X1063980Y623987D01*
X1063360Y622737D01*
X1062895Y621070D01*
X1062740Y619195D01*
X1062895Y617320D01*
X1063360Y615653D01*
X1063980Y614403D01*
X1064910Y613362D01*
X1066150Y612945D01*
X1067390Y613362D01*
X1068320Y614403D01*
X1068940Y615653D01*
X1069405Y617320D01*
X1069560Y619195D01*
X1069405Y621070D01*
X1068940Y622737D01*
X1068320Y623987D01*
X1067390Y625028D01*
X1066150Y625445D01*
G01X1078550Y612528D02*
X1078240Y612737D01*
Y613153D01*
X1078550Y613362D01*
X1078860Y613153D01*
Y612737D01*
X1078550Y612528D01*
G01X1090950Y625445D02*
X1089710Y625028D01*
X1088780Y623987D01*
X1088160Y622737D01*
X1087695Y621070D01*
X1087540Y619195D01*
X1087695Y617320D01*
X1088160Y615653D01*
X1088780Y614403D01*
X1089710Y613362D01*
X1090950Y612945D01*
X1092190Y613362D01*
X1093120Y614403D01*
X1093740Y615653D01*
X1094205Y617320D01*
X1094360Y619195D01*
X1094205Y621070D01*
X1093740Y622737D01*
X1093120Y623987D01*
X1092190Y625028D01*
X1090950Y625445D01*
G01X1053750Y583395D02*
Y595895D01*
X1051890Y593395D01*
G01Y583395D02*
X1055610D01*
G01X1063205Y593812D02*
X1064135Y595061D01*
X1065220Y595687D01*
X1066460Y595895D01*
X1068010Y595478D01*
X1069095Y594437D01*
X1069405Y593187D01*
X1069250Y591936D01*
X1068630Y590895D01*
X1065530Y588812D01*
X1064135Y587353D01*
X1063205Y585270D01*
X1062895Y583395D01*
X1069405D01*
G01X1078550Y582978D02*
X1078240Y583187D01*
Y583603D01*
X1078550Y583812D01*
X1078860Y583603D01*
Y583187D01*
X1078550Y582978D01*
G01X1090950Y595895D02*
X1089710Y595478D01*
X1088780Y594437D01*
X1088160Y593187D01*
X1087695Y591520D01*
X1087540Y589645D01*
X1087695Y587770D01*
X1088160Y586103D01*
X1088780Y584853D01*
X1089710Y583812D01*
X1090950Y583395D01*
X1092190Y583812D01*
X1093120Y584853D01*
X1093740Y586103D01*
X1094205Y587770D01*
X1094360Y589645D01*
X1094205Y591520D01*
X1093740Y593187D01*
X1093120Y594437D01*
X1092190Y595478D01*
X1090950Y595895D01*
G01X1001825Y671420D02*
X1005700Y683920D01*
X1009575Y671420D01*
G01X1008180Y675795D02*
X1003220D01*
G01X1015000Y683920D02*
Y671420D01*
X1021200D01*
G01X1027400Y683920D02*
Y671420D01*
X1033600D01*
G01X1051890Y683920D02*
Y674962D01*
X1052510Y673086D01*
X1053750Y671837D01*
X1055300Y671420D01*
X1056850Y671837D01*
X1058090Y673086D01*
X1058710Y674962D01*
Y683920D01*
G01X1064135Y671420D02*
Y683920D01*
X1071265Y671420D01*
Y683920D01*
G01X1078240D02*
X1081960D01*
G01X1080100D02*
Y671420D01*
G01X1078240D02*
X1081960D01*
G01X1092500Y683920D02*
Y671420D01*
G01X1088935Y683920D02*
X1096065D01*
G01X1101645Y673086D02*
X1102885Y672045D01*
X1104280Y671420D01*
X1105520D01*
X1106760Y672045D01*
X1107690Y673086D01*
X1108155Y674545D01*
X1107845Y676003D01*
X1107070Y677253D01*
X1105675Y678087D01*
X1103815Y678503D01*
X1102730Y679337D01*
X1102265Y680795D01*
X1102575Y682253D01*
X1103350Y683295D01*
X1104435Y683920D01*
X1105520D01*
X1106605Y683503D01*
X1107535Y682462D01*
G01X1125825Y671420D02*
X1129700Y683920D01*
X1133575Y671420D01*
G01X1132180Y675795D02*
X1127220D01*
G01X1139000Y671420D02*
Y683920D01*
X1142875D01*
X1144115Y683295D01*
X1144890Y682462D01*
X1145200Y680795D01*
X1144890Y679128D01*
X1143960Y678087D01*
X1142875Y677462D01*
X1139000D01*
G01X1142875D02*
X1145200Y671420D01*
G01X1157600D02*
X1151400D01*
Y683920D01*
X1157600D01*
G01X1155120Y677878D02*
X1151400D01*
G01X1177440Y683920D02*
X1181160D01*
G01X1179300D02*
Y671420D01*
G01X1177440D02*
X1181160D01*
G01X1188135D02*
Y683920D01*
X1195265Y671420D01*
Y683920D01*
G01X1212470Y671420D02*
Y683920D01*
X1216500Y673503D01*
X1220530Y683920D01*
Y671420D01*
G01X1227040Y683920D02*
X1230760D01*
G01X1228900D02*
Y671420D01*
G01X1227040D02*
X1230760D01*
G01X1238200Y683920D02*
Y671420D01*
X1244400D01*
G01X1250445Y673086D02*
X1251685Y672045D01*
X1253080Y671420D01*
X1254320D01*
X1255560Y672045D01*
X1256490Y673086D01*
X1256955Y674545D01*
X1256645Y676003D01*
X1255870Y677253D01*
X1254475Y678087D01*
X1252615Y678503D01*
X1251530Y679337D01*
X1251065Y680795D01*
X1251375Y682253D01*
X1252150Y683295D01*
X1253235Y683920D01*
X1254320D01*
X1255405Y683503D01*
X1256335Y682462D01*
G01X1050495Y644986D02*
X1051735Y643945D01*
X1053130Y643320D01*
X1054370D01*
X1055610Y643945D01*
X1056540Y644986D01*
X1057005Y646445D01*
X1056695Y647903D01*
X1055920Y649153D01*
X1054525Y649987D01*
X1052665Y650403D01*
X1051580Y651237D01*
X1051115Y652695D01*
X1051425Y654153D01*
X1052200Y655195D01*
X1053285Y655820D01*
X1054370D01*
X1055455Y655403D01*
X1056385Y654362D01*
G01X1064290Y655820D02*
X1068010D01*
G01X1066150D02*
Y643320D01*
G01X1064290D02*
X1068010D01*
G01X1075605Y655820D02*
X1081495D01*
X1075605Y643320D01*
X1081495D01*
G01X1094050D02*
X1087850D01*
Y655820D01*
X1094050D01*
G01X1091570Y649778D02*
X1087850D01*
G01X1171085Y199245D02*
Y211745D01*
X1178215Y199245D01*
Y211745D01*
G01X1187050Y199245D02*
X1185810Y199453D01*
X1184725Y200286D01*
X1183795Y201537D01*
X1183175Y202995D01*
X1182865Y204662D01*
Y206328D01*
X1183175Y207995D01*
X1183795Y209453D01*
X1184725Y210703D01*
X1185810Y211537D01*
X1187050Y211745D01*
X1188290Y211537D01*
X1189375Y210703D01*
X1190305Y209453D01*
X1190925Y207995D01*
X1191235Y206328D01*
Y204662D01*
X1190925Y202995D01*
X1190305Y201537D01*
X1189375Y200286D01*
X1188290Y199453D01*
X1187050Y199245D01*
G01X1195885D02*
Y211745D01*
X1203015Y199245D01*
Y211745D01*
G01X1209835Y203412D02*
X1213865D01*
G01X1221150Y199245D02*
Y211745D01*
X1224870D01*
X1226110Y211120D01*
X1227040Y209662D01*
X1227350Y207995D01*
X1227040Y206328D01*
X1226265Y205078D01*
X1224870Y204453D01*
X1221150D01*
G01X1233550Y211745D02*
Y199245D01*
X1239750D01*
G01X1245175D02*
X1249050Y211745D01*
X1252925Y199245D01*
G01X1251530Y203620D02*
X1246570D01*
G01X1261450Y211745D02*
Y199245D01*
G01X1257885Y211745D02*
X1265015D01*
G01X1276950Y199245D02*
X1270750D01*
Y211745D01*
X1276950D01*
G01X1274470Y205703D02*
X1270750D01*
G01X1282840Y199245D02*
Y211745D01*
X1285940D01*
X1287180Y211120D01*
X1288110Y210287D01*
X1288885Y209037D01*
X1289505Y207578D01*
X1289660Y205495D01*
X1289505Y203412D01*
X1288885Y201953D01*
X1288110Y200703D01*
X1287180Y199870D01*
X1285940Y199245D01*
X1282840D01*
G01X1166900Y662070D02*
Y190720D01*
G01X1171085Y258345D02*
Y270845D01*
X1178215Y258345D01*
Y270845D01*
G01X1187050Y258345D02*
X1185810Y258553D01*
X1184725Y259386D01*
X1183795Y260637D01*
X1183175Y262095D01*
X1182865Y263762D01*
Y265428D01*
X1183175Y267095D01*
X1183795Y268553D01*
X1184725Y269803D01*
X1185810Y270637D01*
X1187050Y270845D01*
X1188290Y270637D01*
X1189375Y269803D01*
X1190305Y268553D01*
X1190925Y267095D01*
X1191235Y265428D01*
Y263762D01*
X1190925Y262095D01*
X1190305Y260637D01*
X1189375Y259386D01*
X1188290Y258553D01*
X1187050Y258345D01*
G01X1195885D02*
Y270845D01*
X1203015Y258345D01*
Y270845D01*
G01X1209835Y262512D02*
X1213865D01*
G01X1221150Y258345D02*
Y270845D01*
X1224870D01*
X1226110Y270220D01*
X1227040Y268762D01*
X1227350Y267095D01*
X1227040Y265428D01*
X1226265Y264178D01*
X1224870Y263553D01*
X1221150D01*
G01X1233550Y270845D02*
Y258345D01*
X1239750D01*
G01X1245175D02*
X1249050Y270845D01*
X1252925Y258345D01*
G01X1251530Y262720D02*
X1246570D01*
G01X1261450Y270845D02*
Y258345D01*
G01X1257885Y270845D02*
X1265015D01*
G01X1276950Y258345D02*
X1270750D01*
Y270845D01*
X1276950D01*
G01X1274470Y264803D02*
X1270750D01*
G01X1282840Y258345D02*
Y270845D01*
X1285940D01*
X1287180Y270220D01*
X1288110Y269387D01*
X1288885Y268137D01*
X1289505Y266678D01*
X1289660Y264595D01*
X1289505Y262512D01*
X1288885Y261053D01*
X1288110Y259803D01*
X1287180Y258970D01*
X1285940Y258345D01*
X1282840D01*
G01X1171085Y228795D02*
Y241295D01*
X1178215Y228795D01*
Y241295D01*
G01X1187050Y228795D02*
X1185810Y229003D01*
X1184725Y229836D01*
X1183795Y231087D01*
X1183175Y232545D01*
X1182865Y234212D01*
Y235878D01*
X1183175Y237545D01*
X1183795Y239003D01*
X1184725Y240253D01*
X1185810Y241087D01*
X1187050Y241295D01*
X1188290Y241087D01*
X1189375Y240253D01*
X1190305Y239003D01*
X1190925Y237545D01*
X1191235Y235878D01*
Y234212D01*
X1190925Y232545D01*
X1190305Y231087D01*
X1189375Y229836D01*
X1188290Y229003D01*
X1187050Y228795D01*
G01X1195885D02*
Y241295D01*
X1203015Y228795D01*
Y241295D01*
G01X1209835Y232962D02*
X1213865D01*
G01X1221150Y228795D02*
Y241295D01*
X1224870D01*
X1226110Y240670D01*
X1227040Y239212D01*
X1227350Y237545D01*
X1227040Y235878D01*
X1226265Y234628D01*
X1224870Y234003D01*
X1221150D01*
G01X1233550Y241295D02*
Y228795D01*
X1239750D01*
G01X1245175D02*
X1249050Y241295D01*
X1252925Y228795D01*
G01X1251530Y233170D02*
X1246570D01*
G01X1261450Y241295D02*
Y228795D01*
G01X1257885Y241295D02*
X1265015D01*
G01X1276950Y228795D02*
X1270750D01*
Y241295D01*
X1276950D01*
G01X1274470Y235253D02*
X1270750D01*
G01X1282840Y228795D02*
Y241295D01*
X1285940D01*
X1287180Y240670D01*
X1288110Y239837D01*
X1288885Y238587D01*
X1289505Y237128D01*
X1289660Y235045D01*
X1289505Y232962D01*
X1288885Y231503D01*
X1288110Y230253D01*
X1287180Y229420D01*
X1285940Y228795D01*
X1282840D01*
G01X1171085Y346995D02*
Y359495D01*
X1178215Y346995D01*
Y359495D01*
G01X1187050Y346995D02*
X1185810Y347203D01*
X1184725Y348036D01*
X1183795Y349287D01*
X1183175Y350745D01*
X1182865Y352412D01*
Y354078D01*
X1183175Y355745D01*
X1183795Y357203D01*
X1184725Y358453D01*
X1185810Y359287D01*
X1187050Y359495D01*
X1188290Y359287D01*
X1189375Y358453D01*
X1190305Y357203D01*
X1190925Y355745D01*
X1191235Y354078D01*
Y352412D01*
X1190925Y350745D01*
X1190305Y349287D01*
X1189375Y348036D01*
X1188290Y347203D01*
X1187050Y346995D01*
G01X1195885D02*
Y359495D01*
X1203015Y346995D01*
Y359495D01*
G01X1209835Y351162D02*
X1213865D01*
G01X1221150Y346995D02*
Y359495D01*
X1224870D01*
X1226110Y358870D01*
X1227040Y357412D01*
X1227350Y355745D01*
X1227040Y354078D01*
X1226265Y352828D01*
X1224870Y352203D01*
X1221150D01*
G01X1233550Y359495D02*
Y346995D01*
X1239750D01*
G01X1245175D02*
X1249050Y359495D01*
X1252925Y346995D01*
G01X1251530Y351370D02*
X1246570D01*
G01X1261450Y359495D02*
Y346995D01*
G01X1257885Y359495D02*
X1265015D01*
G01X1276950Y346995D02*
X1270750D01*
Y359495D01*
X1276950D01*
G01X1274470Y353453D02*
X1270750D01*
G01X1282840Y346995D02*
Y359495D01*
X1285940D01*
X1287180Y358870D01*
X1288110Y358037D01*
X1288885Y356787D01*
X1289505Y355328D01*
X1289660Y353245D01*
X1289505Y351162D01*
X1288885Y349703D01*
X1288110Y348453D01*
X1287180Y347620D01*
X1285940Y346995D01*
X1282840D01*
G01X1171085Y317445D02*
Y329945D01*
X1178215Y317445D01*
Y329945D01*
G01X1187050Y317445D02*
X1185810Y317653D01*
X1184725Y318486D01*
X1183795Y319737D01*
X1183175Y321195D01*
X1182865Y322862D01*
Y324528D01*
X1183175Y326195D01*
X1183795Y327653D01*
X1184725Y328903D01*
X1185810Y329737D01*
X1187050Y329945D01*
X1188290Y329737D01*
X1189375Y328903D01*
X1190305Y327653D01*
X1190925Y326195D01*
X1191235Y324528D01*
Y322862D01*
X1190925Y321195D01*
X1190305Y319737D01*
X1189375Y318486D01*
X1188290Y317653D01*
X1187050Y317445D01*
G01X1195885D02*
Y329945D01*
X1203015Y317445D01*
Y329945D01*
G01X1209835Y321612D02*
X1213865D01*
G01X1221150Y317445D02*
Y329945D01*
X1224870D01*
X1226110Y329320D01*
X1227040Y327862D01*
X1227350Y326195D01*
X1227040Y324528D01*
X1226265Y323278D01*
X1224870Y322653D01*
X1221150D01*
G01X1233550Y329945D02*
Y317445D01*
X1239750D01*
G01X1245175D02*
X1249050Y329945D01*
X1252925Y317445D01*
G01X1251530Y321820D02*
X1246570D01*
G01X1261450Y329945D02*
Y317445D01*
G01X1257885Y329945D02*
X1265015D01*
G01X1276950Y317445D02*
X1270750D01*
Y329945D01*
X1276950D01*
G01X1274470Y323903D02*
X1270750D01*
G01X1282840Y317445D02*
Y329945D01*
X1285940D01*
X1287180Y329320D01*
X1288110Y328487D01*
X1288885Y327237D01*
X1289505Y325778D01*
X1289660Y323695D01*
X1289505Y321612D01*
X1288885Y320153D01*
X1288110Y318903D01*
X1287180Y318070D01*
X1285940Y317445D01*
X1282840D01*
G01X1171085Y287895D02*
Y300395D01*
X1178215Y287895D01*
Y300395D01*
G01X1187050Y287895D02*
X1185810Y288103D01*
X1184725Y288936D01*
X1183795Y290187D01*
X1183175Y291645D01*
X1182865Y293312D01*
Y294978D01*
X1183175Y296645D01*
X1183795Y298103D01*
X1184725Y299353D01*
X1185810Y300187D01*
X1187050Y300395D01*
X1188290Y300187D01*
X1189375Y299353D01*
X1190305Y298103D01*
X1190925Y296645D01*
X1191235Y294978D01*
Y293312D01*
X1190925Y291645D01*
X1190305Y290187D01*
X1189375Y288936D01*
X1188290Y288103D01*
X1187050Y287895D01*
G01X1195885D02*
Y300395D01*
X1203015Y287895D01*
Y300395D01*
G01X1209835Y292062D02*
X1213865D01*
G01X1221150Y287895D02*
Y300395D01*
X1224870D01*
X1226110Y299770D01*
X1227040Y298312D01*
X1227350Y296645D01*
X1227040Y294978D01*
X1226265Y293728D01*
X1224870Y293103D01*
X1221150D01*
G01X1233550Y300395D02*
Y287895D01*
X1239750D01*
G01X1245175D02*
X1249050Y300395D01*
X1252925Y287895D01*
G01X1251530Y292270D02*
X1246570D01*
G01X1261450Y300395D02*
Y287895D01*
G01X1257885Y300395D02*
X1265015D01*
G01X1276950Y287895D02*
X1270750D01*
Y300395D01*
X1276950D01*
G01X1274470Y294353D02*
X1270750D01*
G01X1282840Y287895D02*
Y300395D01*
X1285940D01*
X1287180Y299770D01*
X1288110Y298937D01*
X1288885Y297687D01*
X1289505Y296228D01*
X1289660Y294145D01*
X1289505Y292062D01*
X1288885Y290603D01*
X1288110Y289353D01*
X1287180Y288520D01*
X1285940Y287895D01*
X1282840D01*
G01X1196350Y406095D02*
Y418595D01*
X1200070D01*
X1201310Y417970D01*
X1202240Y416512D01*
X1202550Y414845D01*
X1202240Y413178D01*
X1201465Y411928D01*
X1200070Y411303D01*
X1196350D01*
G01X1208750Y418595D02*
Y406095D01*
X1214950D01*
G01X1220375D02*
X1224250Y418595D01*
X1228125Y406095D01*
G01X1226730Y410470D02*
X1221770D01*
G01X1236650Y418595D02*
Y406095D01*
G01X1233085Y418595D02*
X1240215D01*
G01X1252150Y406095D02*
X1245950D01*
Y418595D01*
X1252150D01*
G01X1249670Y412553D02*
X1245950D01*
G01X1258040Y406095D02*
Y418595D01*
X1261140D01*
X1262380Y417970D01*
X1263310Y417137D01*
X1264085Y415887D01*
X1264705Y414428D01*
X1264860Y412345D01*
X1264705Y410262D01*
X1264085Y408803D01*
X1263310Y407553D01*
X1262380Y406720D01*
X1261140Y406095D01*
X1258040D01*
G01X1196350Y376545D02*
Y389045D01*
X1200070D01*
X1201310Y388420D01*
X1202240Y386962D01*
X1202550Y385295D01*
X1202240Y383628D01*
X1201465Y382378D01*
X1200070Y381753D01*
X1196350D01*
G01X1208750Y389045D02*
Y376545D01*
X1214950D01*
G01X1220375D02*
X1224250Y389045D01*
X1228125Y376545D01*
G01X1226730Y380920D02*
X1221770D01*
G01X1236650Y389045D02*
Y376545D01*
G01X1233085Y389045D02*
X1240215D01*
G01X1252150Y376545D02*
X1245950D01*
Y389045D01*
X1252150D01*
G01X1249670Y383003D02*
X1245950D01*
G01X1258040Y376545D02*
Y389045D01*
X1261140D01*
X1262380Y388420D01*
X1263310Y387587D01*
X1264085Y386337D01*
X1264705Y384878D01*
X1264860Y382795D01*
X1264705Y380712D01*
X1264085Y379253D01*
X1263310Y378003D01*
X1262380Y377170D01*
X1261140Y376545D01*
X1258040D01*
G01X1196350Y465195D02*
Y477695D01*
X1200070D01*
X1201310Y477070D01*
X1202240Y475612D01*
X1202550Y473945D01*
X1202240Y472278D01*
X1201465Y471028D01*
X1200070Y470403D01*
X1196350D01*
G01X1208750Y477695D02*
Y465195D01*
X1214950D01*
G01X1220375D02*
X1224250Y477695D01*
X1228125Y465195D01*
G01X1226730Y469570D02*
X1221770D01*
G01X1236650Y477695D02*
Y465195D01*
G01X1233085Y477695D02*
X1240215D01*
G01X1252150Y465195D02*
X1245950D01*
Y477695D01*
X1252150D01*
G01X1249670Y471653D02*
X1245950D01*
G01X1258040Y465195D02*
Y477695D01*
X1261140D01*
X1262380Y477070D01*
X1263310Y476237D01*
X1264085Y474987D01*
X1264705Y473528D01*
X1264860Y471445D01*
X1264705Y469362D01*
X1264085Y467903D01*
X1263310Y466653D01*
X1262380Y465820D01*
X1261140Y465195D01*
X1258040D01*
G01X1196350Y435645D02*
Y448145D01*
X1200070D01*
X1201310Y447520D01*
X1202240Y446062D01*
X1202550Y444395D01*
X1202240Y442728D01*
X1201465Y441478D01*
X1200070Y440853D01*
X1196350D01*
G01X1208750Y448145D02*
Y435645D01*
X1214950D01*
G01X1220375D02*
X1224250Y448145D01*
X1228125Y435645D01*
G01X1226730Y440020D02*
X1221770D01*
G01X1236650Y448145D02*
Y435645D01*
G01X1233085Y448145D02*
X1240215D01*
G01X1252150Y435645D02*
X1245950D01*
Y448145D01*
X1252150D01*
G01X1249670Y442103D02*
X1245950D01*
G01X1258040Y435645D02*
Y448145D01*
X1261140D01*
X1262380Y447520D01*
X1263310Y446687D01*
X1264085Y445437D01*
X1264705Y443978D01*
X1264860Y441895D01*
X1264705Y439812D01*
X1264085Y438353D01*
X1263310Y437103D01*
X1262380Y436270D01*
X1261140Y435645D01*
X1258040D01*
G01X1196350Y553845D02*
Y566345D01*
X1200070D01*
X1201310Y565720D01*
X1202240Y564262D01*
X1202550Y562595D01*
X1202240Y560928D01*
X1201465Y559678D01*
X1200070Y559053D01*
X1196350D01*
G01X1208750Y566345D02*
Y553845D01*
X1214950D01*
G01X1220375D02*
X1224250Y566345D01*
X1228125Y553845D01*
G01X1226730Y558220D02*
X1221770D01*
G01X1236650Y566345D02*
Y553845D01*
G01X1233085Y566345D02*
X1240215D01*
G01X1252150Y553845D02*
X1245950D01*
Y566345D01*
X1252150D01*
G01X1249670Y560303D02*
X1245950D01*
G01X1258040Y553845D02*
Y566345D01*
X1261140D01*
X1262380Y565720D01*
X1263310Y564887D01*
X1264085Y563637D01*
X1264705Y562178D01*
X1264860Y560095D01*
X1264705Y558012D01*
X1264085Y556553D01*
X1263310Y555303D01*
X1262380Y554470D01*
X1261140Y553845D01*
X1258040D01*
G01X1196350Y524295D02*
Y536795D01*
X1200070D01*
X1201310Y536170D01*
X1202240Y534712D01*
X1202550Y533045D01*
X1202240Y531378D01*
X1201465Y530128D01*
X1200070Y529503D01*
X1196350D01*
G01X1208750Y536795D02*
Y524295D01*
X1214950D01*
G01X1220375D02*
X1224250Y536795D01*
X1228125Y524295D01*
G01X1226730Y528670D02*
X1221770D01*
G01X1236650Y536795D02*
Y524295D01*
G01X1233085Y536795D02*
X1240215D01*
G01X1252150Y524295D02*
X1245950D01*
Y536795D01*
X1252150D01*
G01X1249670Y530753D02*
X1245950D01*
G01X1258040Y524295D02*
Y536795D01*
X1261140D01*
X1262380Y536170D01*
X1263310Y535337D01*
X1264085Y534087D01*
X1264705Y532628D01*
X1264860Y530545D01*
X1264705Y528462D01*
X1264085Y527003D01*
X1263310Y525753D01*
X1262380Y524920D01*
X1261140Y524295D01*
X1258040D01*
G01X1196350Y494745D02*
Y507245D01*
X1200070D01*
X1201310Y506620D01*
X1202240Y505162D01*
X1202550Y503495D01*
X1202240Y501828D01*
X1201465Y500578D01*
X1200070Y499953D01*
X1196350D01*
G01X1208750Y507245D02*
Y494745D01*
X1214950D01*
G01X1220375D02*
X1224250Y507245D01*
X1228125Y494745D01*
G01X1226730Y499120D02*
X1221770D01*
G01X1236650Y507245D02*
Y494745D01*
G01X1233085Y507245D02*
X1240215D01*
G01X1252150Y494745D02*
X1245950D01*
Y507245D01*
X1252150D01*
G01X1249670Y501203D02*
X1245950D01*
G01X1258040Y494745D02*
Y507245D01*
X1261140D01*
X1262380Y506620D01*
X1263310Y505787D01*
X1264085Y504537D01*
X1264705Y503078D01*
X1264860Y500995D01*
X1264705Y498912D01*
X1264085Y497453D01*
X1263310Y496203D01*
X1262380Y495370D01*
X1261140Y494745D01*
X1258040D01*
G01X1196350Y612945D02*
Y625445D01*
X1200070D01*
X1201310Y624820D01*
X1202240Y623362D01*
X1202550Y621695D01*
X1202240Y620028D01*
X1201465Y618778D01*
X1200070Y618153D01*
X1196350D01*
G01X1208750Y625445D02*
Y612945D01*
X1214950D01*
G01X1220375D02*
X1224250Y625445D01*
X1228125Y612945D01*
G01X1226730Y617320D02*
X1221770D01*
G01X1236650Y625445D02*
Y612945D01*
G01X1233085Y625445D02*
X1240215D01*
G01X1252150Y612945D02*
X1245950D01*
Y625445D01*
X1252150D01*
G01X1249670Y619403D02*
X1245950D01*
G01X1258040Y612945D02*
Y625445D01*
X1261140D01*
X1262380Y624820D01*
X1263310Y623987D01*
X1264085Y622737D01*
X1264705Y621278D01*
X1264860Y619195D01*
X1264705Y617112D01*
X1264085Y615653D01*
X1263310Y614403D01*
X1262380Y613570D01*
X1261140Y612945D01*
X1258040D01*
G01X1196350Y583395D02*
Y595895D01*
X1200070D01*
X1201310Y595270D01*
X1202240Y593812D01*
X1202550Y592145D01*
X1202240Y590478D01*
X1201465Y589228D01*
X1200070Y588603D01*
X1196350D01*
G01X1208750Y595895D02*
Y583395D01*
X1214950D01*
G01X1220375D02*
X1224250Y595895D01*
X1228125Y583395D01*
G01X1226730Y587770D02*
X1221770D01*
G01X1236650Y595895D02*
Y583395D01*
G01X1233085Y595895D02*
X1240215D01*
G01X1252150Y583395D02*
X1245950D01*
Y595895D01*
X1252150D01*
G01X1249670Y589853D02*
X1245950D01*
G01X1258040Y583395D02*
Y595895D01*
X1261140D01*
X1262380Y595270D01*
X1263310Y594437D01*
X1264085Y593187D01*
X1264705Y591728D01*
X1264860Y589645D01*
X1264705Y587562D01*
X1264085Y586103D01*
X1263310Y584853D01*
X1262380Y584020D01*
X1261140Y583395D01*
X1258040D01*
G01X1196350Y643320D02*
Y655820D01*
X1200070D01*
X1201310Y655195D01*
X1202240Y653737D01*
X1202550Y652070D01*
X1202240Y650403D01*
X1201465Y649153D01*
X1200070Y648528D01*
X1196350D01*
G01X1208750Y655820D02*
Y643320D01*
X1214950D01*
G01X1220375D02*
X1224250Y655820D01*
X1228125Y643320D01*
G01X1226730Y647695D02*
X1221770D01*
G01X1236650Y655820D02*
Y643320D01*
G01X1233085Y655820D02*
X1240215D01*
G01X1252150Y643320D02*
X1245950D01*
Y655820D01*
X1252150D01*
G01X1249670Y649778D02*
X1245950D01*
G01X1258040Y643320D02*
Y655820D01*
X1261140D01*
X1262380Y655195D01*
X1263310Y654362D01*
X1264085Y653112D01*
X1264705Y651653D01*
X1264860Y649570D01*
X1264705Y647487D01*
X1264085Y646028D01*
X1263310Y644778D01*
X1262380Y643945D01*
X1261140Y643320D01*
X1258040D01*
G01X1332750Y199245D02*
Y211745D01*
X1330890Y209245D01*
G01Y199245D02*
X1334610D01*
G01X1294000Y662070D02*
Y190720D01*
G01X1334610Y258345D02*
Y270845D01*
X1328875Y261887D01*
X1336625D01*
G01X1329805Y239212D02*
X1330735Y240461D01*
X1331820Y241087D01*
X1333060Y241295D01*
X1334610Y240878D01*
X1335695Y239837D01*
X1336005Y238587D01*
X1335850Y237336D01*
X1335230Y236295D01*
X1332130Y234212D01*
X1330735Y232753D01*
X1329805Y230670D01*
X1329495Y228795D01*
X1336005D01*
G01X1329805Y357412D02*
X1330735Y358661D01*
X1331820Y359287D01*
X1333060Y359495D01*
X1334610Y359078D01*
X1335695Y358037D01*
X1336005Y356787D01*
X1335850Y355536D01*
X1335230Y354495D01*
X1332130Y352412D01*
X1330735Y350953D01*
X1329805Y348870D01*
X1329495Y346995D01*
X1336005D01*
G01X1329805Y322653D02*
X1330890Y324112D01*
X1331820Y324945D01*
X1333060Y325362D01*
X1334145Y324945D01*
X1334920Y324112D01*
X1335540Y322862D01*
X1335695Y321403D01*
X1335540Y320153D01*
X1334920Y318903D01*
X1333990Y317862D01*
X1332905Y317445D01*
X1331665Y317862D01*
X1330580Y319111D01*
X1329960Y320987D01*
X1329805Y323070D01*
X1330115Y325778D01*
X1330580Y327237D01*
X1331355Y328695D01*
X1332440Y329737D01*
X1333525Y329945D01*
X1334610Y329528D01*
X1335385Y328487D01*
G01X1332750Y287895D02*
Y300395D01*
X1330890Y297895D01*
G01Y287895D02*
X1334610D01*
G01Y406095D02*
Y418595D01*
X1328875Y409637D01*
X1336625D01*
G01X1334610Y376545D02*
Y389045D01*
X1328875Y380087D01*
X1336625D01*
G01X1334610Y465195D02*
Y477695D01*
X1328875Y468737D01*
X1336625D01*
G01X1323605Y446062D02*
X1324535Y447311D01*
X1325620Y447937D01*
X1326860Y448145D01*
X1328410Y447728D01*
X1329495Y446687D01*
X1329805Y445437D01*
X1329650Y444186D01*
X1329030Y443145D01*
X1325930Y441062D01*
X1324535Y439603D01*
X1323605Y437520D01*
X1323295Y435645D01*
X1329805D01*
G01X1338950Y448145D02*
X1337710Y447728D01*
X1336780Y446687D01*
X1336160Y445437D01*
X1335695Y443770D01*
X1335540Y441895D01*
X1335695Y440020D01*
X1336160Y438353D01*
X1336780Y437103D01*
X1337710Y436062D01*
X1338950Y435645D01*
X1340190Y436062D01*
X1341120Y437103D01*
X1341740Y438353D01*
X1342205Y440020D01*
X1342360Y441895D01*
X1342205Y443770D01*
X1341740Y445437D01*
X1341120Y446687D01*
X1340190Y447728D01*
X1338950Y448145D01*
G01X1316940Y555720D02*
X1317870Y554678D01*
X1318955Y554053D01*
X1320350Y553845D01*
X1321745Y554262D01*
X1322830Y555095D01*
X1323605Y556553D01*
X1323760Y558220D01*
X1323450Y559887D01*
X1322675Y560928D01*
X1321590Y561762D01*
X1320505Y561970D01*
X1319420Y561762D01*
X1318025Y560928D01*
X1318490Y566345D01*
X1322675D01*
G01X1332750D02*
X1331510Y565928D01*
X1330580Y564887D01*
X1329960Y563637D01*
X1329495Y561970D01*
X1329340Y560095D01*
X1329495Y558220D01*
X1329960Y556553D01*
X1330580Y555303D01*
X1331510Y554262D01*
X1332750Y553845D01*
X1333990Y554262D01*
X1334920Y555303D01*
X1335540Y556553D01*
X1336005Y558220D01*
X1336160Y560095D01*
X1336005Y561970D01*
X1335540Y563637D01*
X1334920Y564887D01*
X1333990Y565928D01*
X1332750Y566345D01*
G01X1342205Y564262D02*
X1343135Y565511D01*
X1344220Y566137D01*
X1345460Y566345D01*
X1347010Y565928D01*
X1348095Y564887D01*
X1348405Y563637D01*
X1348250Y562386D01*
X1347630Y561345D01*
X1344530Y559262D01*
X1343135Y557803D01*
X1342205Y555720D01*
X1341895Y553845D01*
X1348405D01*
G01X1326550Y524295D02*
Y536795D01*
X1324690Y534295D01*
G01Y524295D02*
X1328410D01*
G01X1336005Y534712D02*
X1336935Y535961D01*
X1338020Y536587D01*
X1339260Y536795D01*
X1340810Y536378D01*
X1341895Y535337D01*
X1342205Y534087D01*
X1342050Y532836D01*
X1341430Y531795D01*
X1338330Y529712D01*
X1336935Y528253D01*
X1336005Y526170D01*
X1335695Y524295D01*
X1342205D01*
G01X1323605Y505162D02*
X1324535Y506411D01*
X1325620Y507037D01*
X1326860Y507245D01*
X1328410Y506828D01*
X1329495Y505787D01*
X1329805Y504537D01*
X1329650Y503286D01*
X1329030Y502245D01*
X1325930Y500162D01*
X1324535Y498703D01*
X1323605Y496620D01*
X1323295Y494745D01*
X1329805D01*
G01X1336005Y499953D02*
X1337090Y501412D01*
X1338020Y502245D01*
X1339260Y502662D01*
X1340345Y502245D01*
X1341120Y501412D01*
X1341740Y500162D01*
X1341895Y498703D01*
X1341740Y497453D01*
X1341120Y496203D01*
X1340190Y495162D01*
X1339105Y494745D01*
X1337865Y495162D01*
X1336780Y496411D01*
X1336160Y498287D01*
X1336005Y500370D01*
X1336315Y503078D01*
X1336780Y504537D01*
X1337555Y505995D01*
X1338640Y507037D01*
X1339725Y507245D01*
X1340810Y506828D01*
X1341585Y505787D01*
G01X1317405Y618153D02*
X1318490Y619612D01*
X1319420Y620445D01*
X1320660Y620862D01*
X1321745Y620445D01*
X1322520Y619612D01*
X1323140Y618362D01*
X1323295Y616903D01*
X1323140Y615653D01*
X1322520Y614403D01*
X1321590Y613362D01*
X1320505Y612945D01*
X1319265Y613362D01*
X1318180Y614611D01*
X1317560Y616487D01*
X1317405Y618570D01*
X1317715Y621278D01*
X1318180Y622737D01*
X1318955Y624195D01*
X1320040Y625237D01*
X1321125Y625445D01*
X1322210Y625028D01*
X1322985Y623987D01*
G01X1329805Y618153D02*
X1330890Y619612D01*
X1331820Y620445D01*
X1333060Y620862D01*
X1334145Y620445D01*
X1334920Y619612D01*
X1335540Y618362D01*
X1335695Y616903D01*
X1335540Y615653D01*
X1334920Y614403D01*
X1333990Y613362D01*
X1332905Y612945D01*
X1331665Y613362D01*
X1330580Y614611D01*
X1329960Y616487D01*
X1329805Y618570D01*
X1330115Y621278D01*
X1330580Y622737D01*
X1331355Y624195D01*
X1332440Y625237D01*
X1333525Y625445D01*
X1334610Y625028D01*
X1335385Y623987D01*
G01X1345150Y625445D02*
X1343910Y625028D01*
X1342980Y623987D01*
X1342360Y622737D01*
X1341895Y621070D01*
X1341740Y619195D01*
X1341895Y617320D01*
X1342360Y615653D01*
X1342980Y614403D01*
X1343910Y613362D01*
X1345150Y612945D01*
X1346390Y613362D01*
X1347320Y614403D01*
X1347940Y615653D01*
X1348405Y617320D01*
X1348560Y619195D01*
X1348405Y621070D01*
X1347940Y622737D01*
X1347320Y623987D01*
X1346390Y625028D01*
X1345150Y625445D01*
G01X1317715Y584853D02*
X1318800Y583812D01*
X1320040Y583395D01*
X1321280Y583812D01*
X1322365Y585061D01*
X1323140Y586937D01*
X1323450Y588812D01*
Y591103D01*
X1323140Y592978D01*
X1322365Y594645D01*
X1321435Y595478D01*
X1320350Y595895D01*
X1319110Y595478D01*
X1318180Y594645D01*
X1317560Y593395D01*
X1317250Y591728D01*
X1317560Y590270D01*
X1318335Y588812D01*
X1319265Y587978D01*
X1320350Y587770D01*
X1321590Y588186D01*
X1322520Y589228D01*
X1323450Y591103D01*
G01X1332440Y583395D02*
X1332750Y586103D01*
X1333215Y588395D01*
X1333835Y590478D01*
X1334610Y592770D01*
X1335850Y595895D01*
X1329650D01*
G01X1342205Y588603D02*
X1343290Y590062D01*
X1344220Y590895D01*
X1345460Y591312D01*
X1346545Y590895D01*
X1347320Y590062D01*
X1347940Y588812D01*
X1348095Y587353D01*
X1347940Y586103D01*
X1347320Y584853D01*
X1346390Y583812D01*
X1345305Y583395D01*
X1344065Y583812D01*
X1342980Y585061D01*
X1342360Y586937D01*
X1342205Y589020D01*
X1342515Y591728D01*
X1342980Y593187D01*
X1343755Y594645D01*
X1344840Y595687D01*
X1345925Y595895D01*
X1347010Y595478D01*
X1347785Y594437D01*
G01X1320350Y643320D02*
X1319110Y643528D01*
X1318025Y644361D01*
X1317095Y645612D01*
X1316475Y647070D01*
X1316165Y648737D01*
Y650403D01*
X1316475Y652070D01*
X1317095Y653528D01*
X1318025Y654778D01*
X1319110Y655612D01*
X1320350Y655820D01*
X1321590Y655612D01*
X1322675Y654778D01*
X1323605Y653528D01*
X1324225Y652070D01*
X1324535Y650403D01*
Y648737D01*
X1324225Y647070D01*
X1323605Y645612D01*
X1322675Y644361D01*
X1321590Y643528D01*
X1320350Y643320D01*
G01X1321590Y646653D02*
X1323450Y643320D01*
G01X1332750Y655820D02*
Y643320D01*
G01X1329185Y655820D02*
X1336315D01*
G01X1345150Y643320D02*
Y648945D01*
X1342050Y655820D01*
G01X1348250D02*
X1345150Y648945D01*
G54D17*
X22980Y59055D03*
X30854D03*
X22980Y106299D03*
Y98425D03*
Y90551D03*
Y82677D03*
Y74803D03*
Y66929D03*
X30854Y106299D03*
Y98425D03*
Y90551D03*
Y82677D03*
Y74803D03*
Y66929D03*
X41142Y135669D03*
Y155669D03*
Y145669D03*
X26181Y537559D03*
Y527559D03*
Y517559D03*
X41142Y655669D03*
Y645669D03*
Y635669D03*
Y763780D03*
Y753780D03*
Y773780D03*
X932850Y500995D03*
G54D18*
X29528Y19685D03*
X76772D03*
X108268Y905512D03*
X155512D03*
X932850Y382795D03*
G54D19*
X53547Y322486D03*
Y302486D03*
X182681Y580832D03*
Y560832D03*
X932850Y471445D03*
M02*
